(kicad_sch
	(version 20250114)
	(generator "eeschema")
	(generator_version "9.0")
	(paper "A3")
	(title_block
		(title "Thunderbolt to 10GbE adapter")
		(date "2026-04-23")
		(rev "1.1.0")
		(company "Antmicro Ltd")
		(comment 1 "www.antmicro.com")
	)
	(bus_alias "AUX_TB"
		(members "+" "-")
	)
	(text "USB"
		(exclude_from_sim no)
		(at 150.622 29.718 0)
		(effects
			(font
				(size 2.54 2.54)
				(thickness 0.508)
				(bold yes)
			)
			(justify left bottom)
		)
	)
	(text "Thunderbolt Controller"
		(exclude_from_sim no)
		(at 202.692 20.066 0)
		(effects
			(font
				(size 2.54 2.54)
				(thickness 0.508)
				(bold yes)
			)
			(justify left bottom)
		)
	)
	(text "PCIe"
		(exclude_from_sim no)
		(at 288.798 24.892 0)
		(effects
			(font
				(size 2.54 2.54)
				(thickness 0.508)
				(bold yes)
			)
			(justify left bottom)
		)
	)
	(text "PCIe Clock Generator"
		(exclude_from_sim no)
		(at 265.43 95.885 0)
		(effects
			(font
				(size 2.54 2.54)
				(thickness 0.508)
				(bold yes)
			)
			(justify left bottom)
		)
	)
	(text "CONFIG FLASH Connection"
		(exclude_from_sim no)
		(at 190.246 152.146 0)
		(effects
			(font
				(size 2.54 2.54)
				(thickness 0.508)
				(bold yes)
			)
			(justify left bottom)
		)
	)
	(text "DP/GPIO"
		(exclude_from_sim no)
		(at 61.214 150.114 0)
		(effects
			(font
				(size 2.54 2.54)
				(thickness 0.508)
				(bold yes)
			)
			(justify left bottom)
		)
	)
	(junction
		(at 184.15 189.23)
		(diameter 0)
		(color 0 0 0 0)
	)
	(junction
		(at 127 246.38)
		(diameter 0)
		(color 0 0 0 0)
	)
	(junction
		(at 30.48 210.82)
		(diameter 0)
		(color 0 0 0 0)
	)
	(junction
		(at 400.05 203.2)
		(diameter 0)
		(color 0 0 0 0)
	)
	(junction
		(at 196.85 96.52)
		(diameter 0)
		(color 0 0 0 0)
	)
	(junction
		(at 400.05 208.28)
		(diameter 0)
		(color 0 0 0 0)
	)
	(junction
		(at 30.48 261.62)
		(diameter 0)
		(color 0 0 0 0)
	)
	(junction
		(at 340.36 200.66)
		(diameter 0)
		(color 0 0 0 0)
	)
	(junction
		(at 30.48 264.16)
		(diameter 0)
		(color 0 0 0 0)
	)
	(junction
		(at 196.85 93.98)
		(diameter 0)
		(color 0 0 0 0)
	)
	(junction
		(at 400.05 200.66)
		(diameter 0)
		(color 0 0 0 0)
	)
	(junction
		(at 113.03 228.6)
		(diameter 0)
		(color 0 0 0 0)
	)
	(junction
		(at 30.48 208.28)
		(diameter 0)
		(color 0 0 0 0)
	)
	(junction
		(at 30.48 269.24)
		(diameter 0)
		(color 0 0 0 0)
	)
	(junction
		(at 113.03 236.22)
		(diameter 0)
		(color 0 0 0 0)
	)
	(junction
		(at 243.84 128.27)
		(diameter 0)
		(color 0 0 0 0)
	)
	(junction
		(at 309.88 190.5)
		(diameter 0)
		(color 0 0 0 0)
	)
	(junction
		(at 364.49 34.29)
		(diameter 0)
		(color 0 0 0 0)
	)
	(junction
		(at 340.36 203.2)
		(diameter 0)
		(color 0 0 0 0)
	)
	(junction
		(at 113.03 251.46)
		(diameter 0)
		(color 0 0 0 0)
	)
	(junction
		(at 184.15 184.15)
		(diameter 0)
		(color 0 0 0 0)
	)
	(junction
		(at 102.87 93.98)
		(diameter 0)
		(color 0 0 0 0)
	)
	(junction
		(at 336.55 78.74)
		(diameter 0)
		(color 0 0 0 0)
	)
	(junction
		(at 271.78 107.95)
		(diameter 0)
		(color 0 0 0 0)
	)
	(junction
		(at 269.24 186.69)
		(diameter 0)
		(color 0 0 0 0)
	)
	(junction
		(at 254 128.27)
		(diameter 0)
		(color 0 0 0 0)
	)
	(junction
		(at 106.68 91.44)
		(diameter 0)
		(color 0 0 0 0)
	)
	(junction
		(at 113.03 226.06)
		(diameter 0)
		(color 0 0 0 0)
	)
	(junction
		(at 113.03 256.54)
		(diameter 0)
		(color 0 0 0 0)
	)
	(junction
		(at 299.72 196.85)
		(diameter 0)
		(color 0 0 0 0)
	)
	(junction
		(at 113.03 259.08)
		(diameter 0)
		(color 0 0 0 0)
	)
	(junction
		(at 113.03 233.68)
		(diameter 0)
		(color 0 0 0 0)
	)
	(junction
		(at 254 118.11)
		(diameter 0)
		(color 0 0 0 0)
	)
	(junction
		(at 113.03 231.14)
		(diameter 0)
		(color 0 0 0 0)
	)
	(junction
		(at 243.84 123.19)
		(diameter 0)
		(color 0 0 0 0)
	)
	(junction
		(at 184.15 186.69)
		(diameter 0)
		(color 0 0 0 0)
	)
	(junction
		(at 309.88 196.85)
		(diameter 0)
		(color 0 0 0 0)
	)
	(junction
		(at 196.85 101.6)
		(diameter 0)
		(color 0 0 0 0)
	)
	(junction
		(at 299.72 185.42)
		(diameter 0)
		(color 0 0 0 0)
	)
	(junction
		(at 127 254)
		(diameter 0)
		(color 0 0 0 0)
	)
	(junction
		(at 113.03 208.28)
		(diameter 0)
		(color 0 0 0 0)
	)
	(junction
		(at 340.36 210.82)
		(diameter 0)
		(color 0 0 0 0)
	)
	(junction
		(at 340.36 208.28)
		(diameter 0)
		(color 0 0 0 0)
	)
	(no_connect
		(at 41.91 228.6)
	)
	(no_connect
		(at 182.88 60.96)
	)
	(no_connect
		(at 97.79 182.88)
	)
	(no_connect
		(at 397.51 187.96)
	)
	(no_connect
		(at 97.79 167.64)
	)
	(no_connect
		(at 41.91 236.22)
	)
	(no_connect
		(at 41.91 226.06)
	)
	(no_connect
		(at 397.51 195.58)
	)
	(no_connect
		(at 182.88 48.26)
	)
	(no_connect
		(at 182.88 86.36)
	)
	(no_connect
		(at 182.88 68.58)
	)
	(no_connect
		(at 97.79 172.72)
	)
	(no_connect
		(at 41.91 195.58)
	)
	(no_connect
		(at 97.79 195.58)
	)
	(no_connect
		(at 182.88 83.82)
	)
	(no_connect
		(at 41.91 218.44)
	)
	(no_connect
		(at 41.91 243.84)
	)
	(no_connect
		(at 41.91 180.34)
	)
	(no_connect
		(at 341.63 185.42)
	)
	(no_connect
		(at 41.91 165.1)
	)
	(no_connect
		(at 41.91 190.5)
	)
	(no_connect
		(at 341.63 182.88)
	)
	(no_connect
		(at 182.88 76.2)
	)
	(no_connect
		(at 182.88 55.88)
	)
	(no_connect
		(at 97.79 190.5)
	)
	(no_connect
		(at 41.91 172.72)
	)
	(no_connect
		(at 397.51 190.5)
	)
	(no_connect
		(at 41.91 198.12)
	)
	(no_connect
		(at 97.79 187.96)
	)
	(no_connect
		(at 41.91 187.96)
	)
	(no_connect
		(at 97.79 175.26)
	)
	(no_connect
		(at 182.88 45.72)
	)
	(no_connect
		(at 41.91 233.68)
	)
	(no_connect
		(at 41.91 175.26)
	)
	(no_connect
		(at 41.91 241.3)
	)
	(no_connect
		(at 182.88 53.34)
	)
	(no_connect
		(at 97.79 180.34)
	)
	(no_connect
		(at 41.91 251.46)
	)
	(no_connect
		(at 41.91 248.92)
	)
	(no_connect
		(at 97.79 198.12)
	)
	(no_connect
		(at 97.79 165.1)
	)
	(no_connect
		(at 41.91 182.88)
	)
	(no_connect
		(at 182.88 78.74)
	)
	(no_connect
		(at 182.88 71.12)
	)
	(no_connect
		(at 41.91 167.64)
	)
	(no_connect
		(at 182.88 63.5)
	)
	(no_connect
		(at 41.91 220.98)
	)
	(no_connect
		(at 341.63 190.5)
	)
	(bus_entry
		(at 245.11 67.31)
		(size 1.27 1.27)
		(stroke
			(width 0)
			(type default)
		)
	)
	(bus_entry
		(at 71.12 44.45)
		(size 1.27 1.27)
		(stroke
			(width 0)
			(type default)
		)
	)
	(bus_entry
		(at 364.49 46.99)
		(size -1.27 1.27)
		(stroke
			(width 0)
			(type default)
		)
	)
	(bus_entry
		(at 364.49 44.45)
		(size -1.27 1.27)
		(stroke
			(width 0)
			(type default)
		)
	)
	(bus_entry
		(at 364.49 54.61)
		(size -1.27 1.27)
		(stroke
			(width 0)
			(type default)
		)
	)
	(bus_entry
		(at 364.49 67.31)
		(size -1.27 1.27)
		(stroke
			(width 0)
			(type default)
		)
	)
	(bus_entry
		(at 283.21 203.2)
		(size -1.27 1.27)
		(stroke
			(width 0)
			(type default)
		)
	)
	(bus_entry
		(at 364.49 59.69)
		(size -1.27 1.27)
		(stroke
			(width 0)
			(type default)
		)
	)
	(bus_entry
		(at 320.04 125.73)
		(size -1.27 -1.27)
		(stroke
			(width 0)
			(type default)
		)
	)
	(bus_entry
		(at 320.04 128.27)
		(size -1.27 -1.27)
		(stroke
			(width 0)
			(type default)
		)
	)
	(bus_entry
		(at 71.12 76.2)
		(size 2.54 2.54)
		(stroke
			(width 0)
			(type default)
		)
	)
	(bus_entry
		(at 245.11 62.23)
		(size 1.27 1.27)
		(stroke
			(width 0)
			(type default)
		)
	)
	(bus_entry
		(at 71.12 91.44)
		(size 2.54 2.54)
		(stroke
			(width 0)
			(type default)
		)
	)
	(bus_entry
		(at 283.21 208.28)
		(size -1.27 1.27)
		(stroke
			(width 0)
			(type default)
		)
	)
	(bus_entry
		(at 245.11 52.07)
		(size 1.27 1.27)
		(stroke
			(width 0)
			(type default)
		)
	)
	(bus_entry
		(at 245.11 59.69)
		(size 1.27 1.27)
		(stroke
			(width 0)
			(type default)
		)
	)
	(bus_entry
		(at 364.49 62.23)
		(size -1.27 1.27)
		(stroke
			(width 0)
			(type default)
		)
	)
	(bus_entry
		(at 137.16 219.71)
		(size -1.27 1.27)
		(stroke
			(width 0)
			(type default)
		)
	)
	(bus_entry
		(at 71.12 69.85)
		(size 1.27 1.27)
		(stroke
			(width 0)
			(type default)
		)
	)
	(bus_entry
		(at 283.21 200.66)
		(size -1.27 1.27)
		(stroke
			(width 0)
			(type default)
		)
	)
	(bus_entry
		(at 245.11 46.99)
		(size 1.27 1.27)
		(stroke
			(width 0)
			(type default)
		)
	)
	(bus_entry
		(at 283.21 205.74)
		(size -1.27 1.27)
		(stroke
			(width 0)
			(type default)
		)
	)
	(bus_entry
		(at 364.49 69.85)
		(size -1.27 1.27)
		(stroke
			(width 0)
			(type default)
		)
	)
	(bus_entry
		(at 71.12 46.99)
		(size 1.27 1.27)
		(stroke
			(width 0)
			(type default)
		)
	)
	(bus_entry
		(at 71.12 73.66)
		(size 2.54 2.54)
		(stroke
			(width 0)
			(type default)
		)
	)
	(bus_entry
		(at 71.12 59.69)
		(size 1.27 1.27)
		(stroke
			(width 0)
			(type default)
		)
	)
	(bus_entry
		(at 245.11 44.45)
		(size 1.27 1.27)
		(stroke
			(width 0)
			(type default)
		)
	)
	(bus_entry
		(at 71.12 88.9)
		(size 2.54 2.54)
		(stroke
			(width 0)
			(type default)
		)
	)
	(bus_entry
		(at 71.12 54.61)
		(size 1.27 1.27)
		(stroke
			(width 0)
			(type default)
		)
	)
	(bus_entry
		(at 364.49 52.07)
		(size -1.27 1.27)
		(stroke
			(width 0)
			(type default)
		)
	)
	(bus_entry
		(at 137.16 217.17)
		(size -1.27 1.27)
		(stroke
			(width 0)
			(type default)
		)
	)
	(bus_entry
		(at 71.12 83.82)
		(size 2.54 2.54)
		(stroke
			(width 0)
			(type default)
		)
	)
	(bus_entry
		(at 137.16 214.63)
		(size -1.27 1.27)
		(stroke
			(width 0)
			(type default)
		)
	)
	(bus_entry
		(at 71.12 81.28)
		(size 2.54 2.54)
		(stroke
			(width 0)
			(type default)
		)
	)
	(bus_entry
		(at 71.12 67.31)
		(size 1.27 1.27)
		(stroke
			(width 0)
			(type default)
		)
	)
	(bus_entry
		(at 71.12 62.23)
		(size 1.27 1.27)
		(stroke
			(width 0)
			(type default)
		)
	)
	(bus_entry
		(at 71.12 52.07)
		(size 1.27 1.27)
		(stroke
			(width 0)
			(type default)
		)
	)
	(bus_entry
		(at 245.11 54.61)
		(size 1.27 1.27)
		(stroke
			(width 0)
			(type default)
		)
	)
	(bus_entry
		(at 245.11 69.85)
		(size 1.27 1.27)
		(stroke
			(width 0)
			(type default)
		)
	)
	(wire
		(pts
			(xy 299.72 186.69) (xy 299.72 185.42)
		)
		(stroke
			(width 0)
			(type default)
		)
	)
	(wire
		(pts
			(xy 196.85 91.44) (xy 196.85 93.98)
		)
		(stroke
			(width 0)
			(type default)
		)
	)
	(wire
		(pts
			(xy 346.71 63.5) (xy 363.22 63.5)
		)
		(stroke
			(width 0)
			(type default)
		)
	)
	(wire
		(pts
			(xy 307.34 196.85) (xy 309.88 196.85)
		)
		(stroke
			(width 0)
			(type default)
		)
	)
	(wire
		(pts
			(xy 243.84 118.11) (xy 246.38 118.11)
		)
		(stroke
			(width 0)
			(type default)
		)
	)
	(wire
		(pts
			(xy 97.79 226.06) (xy 101.6 226.06)
		)
		(stroke
			(width 0)
			(type default)
		)
	)
	(wire
		(pts
			(xy 346.71 71.12) (xy 363.22 71.12)
		)
		(stroke
			(width 0)
			(type default)
		)
	)
	(wire
		(pts
			(xy 227.33 76.2) (xy 262.89 76.2)
		)
		(stroke
			(width 0)
			(type default)
		)
	)
	(wire
		(pts
			(xy 400.05 203.2) (xy 400.05 208.28)
		)
		(stroke
			(width 0)
			(type default)
		)
	)
	(wire
		(pts
			(xy 97.79 259.08) (xy 101.6 259.08)
		)
		(stroke
			(width 0)
			(type default)
		)
	)
	(bus
		(pts
			(xy 364.49 34.29) (xy 364.49 44.45)
		)
		(stroke
			(width 0)
			(type default)
		)
	)
	(bus
		(pts
			(xy 137.16 214.63) (xy 137.16 217.17)
		)
		(stroke
			(width 0)
			(type default)
		)
	)
	(wire
		(pts
			(xy 346.71 48.26) (xy 363.22 48.26)
		)
		(stroke
			(width 0)
			(type default)
		)
	)
	(wire
		(pts
			(xy 97.79 228.6) (xy 101.6 228.6)
		)
		(stroke
			(width 0)
			(type default)
		)
	)
	(wire
		(pts
			(xy 196.85 101.6) (xy 196.85 102.87)
		)
		(stroke
			(width 0)
			(type default)
		)
	)
	(wire
		(pts
			(xy 97.79 223.52) (xy 101.6 223.52)
		)
		(stroke
			(width 0)
			(type default)
		)
	)
	(wire
		(pts
			(xy 177.8 184.15) (xy 184.15 184.15)
		)
		(stroke
			(width 0)
			(type default)
		)
	)
	(bus
		(pts
			(xy 71.12 67.31) (xy 71.12 69.85)
		)
		(stroke
			(width 0)
			(type default)
		)
	)
	(wire
		(pts
			(xy 243.84 123.19) (xy 243.84 128.27)
		)
		(stroke
			(width 0)
			(type default)
		)
	)
	(wire
		(pts
			(xy 113.03 231.14) (xy 113.03 228.6)
		)
		(stroke
			(width 0)
			(type default)
		)
	)
	(bus
		(pts
			(xy 137.16 217.17) (xy 137.16 219.71)
		)
		(stroke
			(width 0)
			(type default)
		)
	)
	(wire
		(pts
			(xy 336.55 78.74) (xy 341.63 78.74)
		)
		(stroke
			(width 0)
			(type default)
		)
	)
	(wire
		(pts
			(xy 97.79 215.9) (xy 135.89 215.9)
		)
		(stroke
			(width 0)
			(type default)
		)
	)
	(bus
		(pts
			(xy 68.58 87.63) (xy 69.85 87.63)
		)
		(stroke
			(width 0)
			(type default)
		)
	)
	(wire
		(pts
			(xy 72.39 48.26) (xy 127 48.26)
		)
		(stroke
			(width 0)
			(type default)
		)
	)
	(wire
		(pts
			(xy 243.84 118.11) (xy 243.84 123.19)
		)
		(stroke
			(width 0)
			(type default)
		)
	)
	(wire
		(pts
			(xy 106.68 259.08) (xy 113.03 259.08)
		)
		(stroke
			(width 0)
			(type default)
		)
	)
	(wire
		(pts
			(xy 346.71 55.88) (xy 363.22 55.88)
		)
		(stroke
			(width 0)
			(type default)
		)
	)
	(wire
		(pts
			(xy 73.66 83.82) (xy 127 83.82)
		)
		(stroke
			(width 0)
			(type default)
		)
	)
	(wire
		(pts
			(xy 38.1 269.24) (xy 41.91 269.24)
		)
		(stroke
			(width 0)
			(type default)
		)
	)
	(wire
		(pts
			(xy 97.79 236.22) (xy 101.6 236.22)
		)
		(stroke
			(width 0)
			(type default)
		)
	)
	(wire
		(pts
			(xy 269.24 186.69) (xy 269.24 187.96)
		)
		(stroke
			(width 0)
			(type default)
		)
	)
	(wire
		(pts
			(xy 340.36 200.66) (xy 341.63 200.66)
		)
		(stroke
			(width 0)
			(type default)
		)
	)
	(wire
		(pts
			(xy 97.79 231.14) (xy 101.6 231.14)
		)
		(stroke
			(width 0)
			(type default)
		)
	)
	(wire
		(pts
			(xy 246.38 48.26) (xy 262.89 48.26)
		)
		(stroke
			(width 0)
			(type default)
		)
	)
	(wire
		(pts
			(xy 340.36 195.58) (xy 341.63 195.58)
		)
		(stroke
			(width 0)
			(type default)
		)
	)
	(wire
		(pts
			(xy 113.03 237.49) (xy 113.03 236.22)
		)
		(stroke
			(width 0)
			(type default)
		)
	)
	(wire
		(pts
			(xy 38.1 208.28) (xy 41.91 208.28)
		)
		(stroke
			(width 0)
			(type default)
		)
	)
	(wire
		(pts
			(xy 105.41 60.96) (xy 127 60.96)
		)
		(stroke
			(width 0)
			(type default)
		)
	)
	(wire
		(pts
			(xy 344.17 60.96) (xy 363.22 60.96)
		)
		(stroke
			(width 0)
			(type default)
		)
	)
	(bus
		(pts
			(xy 364.49 59.69) (xy 364.49 62.23)
		)
		(stroke
			(width 0)
			(type default)
		)
	)
	(wire
		(pts
			(xy 269.24 124.46) (xy 278.13 124.46)
		)
		(stroke
			(width 0)
			(type default)
		)
	)
	(wire
		(pts
			(xy 344.17 53.34) (xy 363.22 53.34)
		)
		(stroke
			(width 0)
			(type default)
		)
	)
	(wire
		(pts
			(xy 30.48 203.2) (xy 33.02 203.2)
		)
		(stroke
			(width 0)
			(type default)
		)
	)
	(wire
		(pts
			(xy 309.88 196.85) (xy 309.88 199.39)
		)
		(stroke
			(width 0)
			(type default)
		)
	)
	(wire
		(pts
			(xy 254 186.69) (xy 257.81 186.69)
		)
		(stroke
			(width 0)
			(type default)
		)
	)
	(wire
		(pts
			(xy 254 209.55) (xy 281.94 209.55)
		)
		(stroke
			(width 0)
			(type default)
		)
	)
	(wire
		(pts
			(xy 30.48 270.51) (xy 30.48 269.24)
		)
		(stroke
			(width 0)
			(type default)
		)
	)
	(wire
		(pts
			(xy 322.58 100.33) (xy 227.33 100.33)
		)
		(stroke
			(width 0)
			(type default)
		)
	)
	(wire
		(pts
			(xy 113.03 209.55) (xy 113.03 208.28)
		)
		(stroke
			(width 0)
			(type default)
		)
	)
	(wire
		(pts
			(xy 340.36 195.58) (xy 340.36 200.66)
		)
		(stroke
			(width 0)
			(type default)
		)
	)
	(bus
		(pts
			(xy 69.85 71.12) (xy 71.12 72.39)
		)
		(stroke
			(width 0)
			(type default)
		)
	)
	(wire
		(pts
			(xy 276.86 107.95) (xy 276.86 119.38)
		)
		(stroke
			(width 0)
			(type default)
		)
	)
	(wire
		(pts
			(xy 127 246.38) (xy 127 247.65)
		)
		(stroke
			(width 0)
			(type default)
		)
	)
	(wire
		(pts
			(xy 254 201.93) (xy 281.94 201.93)
		)
		(stroke
			(width 0)
			(type default)
		)
	)
	(polyline
		(pts
			(xy 330.2 142.24) (xy 330.2 248.92)
		)
		(stroke
			(width 0)
			(type default)
		)
	)
	(wire
		(pts
			(xy 318.77 68.58) (xy 339.09 68.58)
		)
		(stroke
			(width 0)
			(type default)
		)
	)
	(wire
		(pts
			(xy 113.03 236.22) (xy 113.03 233.68)
		)
		(stroke
			(width 0)
			(type default)
		)
	)
	(wire
		(pts
			(xy 254 128.27) (xy 269.24 128.27)
		)
		(stroke
			(width 0)
			(type default)
		)
	)
	(wire
		(pts
			(xy 304.8 190.5) (xy 309.88 190.5)
		)
		(stroke
			(width 0)
			(type default)
		)
	)
	(wire
		(pts
			(xy 307.34 185.42) (xy 309.88 185.42)
		)
		(stroke
			(width 0)
			(type default)
		)
	)
	(bus
		(pts
			(xy 364.49 34.29) (xy 374.65 34.29)
		)
		(stroke
			(width 0)
			(type default)
		)
	)
	(polyline
		(pts
			(xy 157.48 142.24) (xy 157.48 279.4)
		)
		(stroke
			(width 0)
			(type default)
		)
	)
	(bus
		(pts
			(xy 320.04 129.54) (xy 320.04 128.27)
		)
		(stroke
			(width 0)
			(type default)
		)
	)
	(wire
		(pts
			(xy 194.31 189.23) (xy 198.12 189.23)
		)
		(stroke
			(width 0)
			(type default)
		)
	)
	(wire
		(pts
			(xy 325.12 121.92) (xy 325.12 111.125)
		)
		(stroke
			(width 0)
			(type default)
		)
	)
	(wire
		(pts
			(xy 259.08 85.09) (xy 260.35 85.09)
		)
		(stroke
			(width 0)
			(type default)
		)
	)
	(bus
		(pts
			(xy 364.49 67.31) (xy 364.49 69.85)
		)
		(stroke
			(width 0)
			(type default)
		)
	)
	(wire
		(pts
			(xy 260.35 85.09) (xy 260.35 83.82)
		)
		(stroke
			(width 0)
			(type default)
		)
	)
	(bus
		(pts
			(xy 67.31 71.12) (xy 69.85 71.12)
		)
		(stroke
			(width 0)
			(type default)
		)
	)
	(bus
		(pts
			(xy 245.11 44.45) (xy 245.11 46.99)
		)
		(stroke
			(width 0)
			(type default)
		)
	)
	(wire
		(pts
			(xy 322.58 108.585) (xy 325.12 111.125)
		)
		(stroke
			(width 0)
			(type default)
		)
	)
	(wire
		(pts
			(xy 102.87 93.98) (xy 102.87 97.79)
		)
		(stroke
			(width 0)
			(type default)
		)
	)
	(wire
		(pts
			(xy 195.58 196.85) (xy 195.58 200.66)
		)
		(stroke
			(width 0)
			(type default)
		)
	)
	(polyline
		(pts
			(xy 15.24 139.7) (xy 406.4 139.7)
		)
		(stroke
			(width 0)
			(type default)
		)
	)
	(wire
		(pts
			(xy 246.38 68.58) (xy 262.89 68.58)
		)
		(stroke
			(width 0)
			(type default)
		)
	)
	(wire
		(pts
			(xy 38.1 256.54) (xy 41.91 256.54)
		)
		(stroke
			(width 0)
			(type default)
		)
	)
	(wire
		(pts
			(xy 254 119.38) (xy 254 118.11)
		)
		(stroke
			(width 0)
			(type default)
		)
	)
	(wire
		(pts
			(xy 113.03 259.08) (xy 113.03 260.35)
		)
		(stroke
			(width 0)
			(type default)
		)
	)
	(wire
		(pts
			(xy 254 118.11) (xy 269.24 118.11)
		)
		(stroke
			(width 0)
			(type default)
		)
	)
	(wire
		(pts
			(xy 72.39 53.34) (xy 127 53.34)
		)
		(stroke
			(width 0)
			(type default)
		)
	)
	(wire
		(pts
			(xy 340.36 203.2) (xy 340.36 208.28)
		)
		(stroke
			(width 0)
			(type default)
		)
	)
	(wire
		(pts
			(xy 97.79 251.46) (xy 101.6 251.46)
		)
		(stroke
			(width 0)
			(type default)
		)
	)
	(wire
		(pts
			(xy 262.89 184.15) (xy 269.24 184.15)
		)
		(stroke
			(width 0)
			(type default)
		)
	)
	(wire
		(pts
			(xy 246.38 71.12) (xy 262.89 71.12)
		)
		(stroke
			(width 0)
			(type default)
		)
	)
	(wire
		(pts
			(xy 100.33 220.98) (xy 97.79 220.98)
		)
		(stroke
			(width 0)
			(type default)
		)
	)
	(wire
		(pts
			(xy 182.88 93.98) (xy 185.42 93.98)
		)
		(stroke
			(width 0)
			(type default)
		)
	)
	(wire
		(pts
			(xy 243.84 123.19) (xy 248.92 123.19)
		)
		(stroke
			(width 0)
			(type default)
		)
	)
	(wire
		(pts
			(xy 177.8 181.61) (xy 177.8 184.15)
		)
		(stroke
			(width 0)
			(type default)
		)
	)
	(wire
		(pts
			(xy 400.05 208.28) (xy 400.05 210.82)
		)
		(stroke
			(width 0)
			(type default)
		)
	)
	(wire
		(pts
			(xy 254 194.31) (xy 281.94 194.31)
		)
		(stroke
			(width 0)
			(type default)
		)
	)
	(wire
		(pts
			(xy 182.88 96.52) (xy 185.42 96.52)
		)
		(stroke
			(width 0)
			(type default)
		)
	)
	(wire
		(pts
			(xy 318.77 48.26) (xy 341.63 48.26)
		)
		(stroke
			(width 0)
			(type default)
		)
	)
	(wire
		(pts
			(xy 100.33 219.71) (xy 101.6 219.71)
		)
		(stroke
			(width 0)
			(type default)
		)
	)
	(wire
		(pts
			(xy 102.87 102.87) (xy 102.87 105.41)
		)
		(stroke
			(width 0)
			(type default)
		)
	)
	(wire
		(pts
			(xy 73.66 78.74) (xy 105.41 78.74)
		)
		(stroke
			(width 0)
			(type default)
		)
	)
	(wire
		(pts
			(xy 397.51 182.88) (xy 400.05 182.88)
		)
		(stroke
			(width 0)
			(type default)
		)
	)
	(wire
		(pts
			(xy 246.38 63.5) (xy 262.89 63.5)
		)
		(stroke
			(width 0)
			(type default)
		)
	)
	(wire
		(pts
			(xy 100.33 219.71) (xy 100.33 220.98)
		)
		(stroke
			(width 0)
			(type default)
		)
	)
	(wire
		(pts
			(xy 106.68 233.68) (xy 113.03 233.68)
		)
		(stroke
			(width 0)
			(type default)
		)
	)
	(wire
		(pts
			(xy 124.46 101.6) (xy 127 101.6)
		)
		(stroke
			(width 0)
			(type default)
		)
	)
	(wire
		(pts
			(xy 229.87 78.74) (xy 262.89 78.74)
		)
		(stroke
			(width 0)
			(type default)
		)
	)
	(wire
		(pts
			(xy 106.68 246.38) (xy 127 246.38)
		)
		(stroke
			(width 0)
			(type default)
		)
	)
	(wire
		(pts
			(xy 184.15 191.77) (xy 189.23 191.77)
		)
		(stroke
			(width 0)
			(type default)
		)
	)
	(wire
		(pts
			(xy 30.48 208.28) (xy 30.48 203.2)
		)
		(stroke
			(width 0)
			(type default)
		)
	)
	(wire
		(pts
			(xy 38.1 264.16) (xy 41.91 264.16)
		)
		(stroke
			(width 0)
			(type default)
		)
	)
	(wire
		(pts
			(xy 254 184.15) (xy 257.81 184.15)
		)
		(stroke
			(width 0)
			(type default)
		)
	)
	(wire
		(pts
			(xy 271.78 107.95) (xy 271.78 109.22)
		)
		(stroke
			(width 0)
			(type default)
		)
	)
	(wire
		(pts
			(xy 269.24 121.92) (xy 278.13 121.92)
		)
		(stroke
			(width 0)
			(type default)
		)
	)
	(bus
		(pts
			(xy 246.38 34.29) (xy 364.49 34.29)
		)
		(stroke
			(width 0)
			(type default)
		)
	)
	(wire
		(pts
			(xy 30.48 256.54) (xy 33.02 256.54)
		)
		(stroke
			(width 0)
			(type default)
		)
	)
	(wire
		(pts
			(xy 30.48 210.82) (xy 30.48 208.28)
		)
		(stroke
			(width 0)
			(type default)
		)
	)
	(wire
		(pts
			(xy 318.77 78.74) (xy 336.55 78.74)
		)
		(stroke
			(width 0)
			(type default)
		)
	)
	(wire
		(pts
			(xy 254 196.85) (xy 299.72 196.85)
		)
		(stroke
			(width 0)
			(type default)
		)
	)
	(wire
		(pts
			(xy 38.1 210.82) (xy 41.91 210.82)
		)
		(stroke
			(width 0)
			(type default)
		)
	)
	(wire
		(pts
			(xy 278.13 119.38) (xy 276.86 119.38)
		)
		(stroke
			(width 0)
			(type default)
		)
	)
	(wire
		(pts
			(xy 190.5 93.98) (xy 196.85 93.98)
		)
		(stroke
			(width 0)
			(type default)
		)
	)
	(wire
		(pts
			(xy 106.68 251.46) (xy 113.03 251.46)
		)
		(stroke
			(width 0)
			(type default)
		)
	)
	(bus
		(pts
			(xy 71.12 72.39) (xy 71.12 73.66)
		)
		(stroke
			(width 0)
			(type default)
		)
	)
	(wire
		(pts
			(xy 400.05 182.88) (xy 400.05 200.66)
		)
		(stroke
			(width 0)
			(type default)
		)
	)
	(wire
		(pts
			(xy 318.77 55.88) (xy 341.63 55.88)
		)
		(stroke
			(width 0)
			(type default)
		)
	)
	(wire
		(pts
			(xy 184.15 186.69) (xy 184.15 184.15)
		)
		(stroke
			(width 0)
			(type default)
		)
	)
	(wire
		(pts
			(xy 113.03 251.46) (xy 113.03 256.54)
		)
		(stroke
			(width 0)
			(type default)
		)
	)
	(wire
		(pts
			(xy 106.68 91.44) (xy 106.68 97.79)
		)
		(stroke
			(width 0)
			(type default)
		)
	)
	(bus
		(pts
			(xy 71.12 54.61) (xy 71.12 59.69)
		)
		(stroke
			(width 0)
			(type default)
		)
	)
	(bus
		(pts
			(xy 320.04 128.27) (xy 320.04 125.73)
		)
		(stroke
			(width 0)
			(type default)
		)
	)
	(bus
		(pts
			(xy 323.85 130.81) (xy 321.31 130.81)
		)
		(stroke
			(width 0)
			(type default)
		)
	)
	(wire
		(pts
			(xy 269.24 118.11) (xy 269.24 121.92)
		)
		(stroke
			(width 0)
			(type default)
		)
	)
	(wire
		(pts
			(xy 184.15 189.23) (xy 184.15 186.69)
		)
		(stroke
			(width 0)
			(type default)
		)
	)
	(wire
		(pts
			(xy 254 189.23) (xy 255.27 189.23)
		)
		(stroke
			(width 0)
			(type default)
		)
	)
	(wire
		(pts
			(xy 252.73 83.82) (xy 252.73 85.09)
		)
		(stroke
			(width 0)
			(type default)
		)
	)
	(bus
		(pts
			(xy 283.21 203.2) (xy 283.21 205.74)
		)
		(stroke
			(width 0)
			(type default)
		)
	)
	(bus
		(pts
			(xy 71.12 43.18) (xy 71.12 44.45)
		)
		(stroke
			(width 0)
			(type default)
		)
	)
	(wire
		(pts
			(xy 246.38 55.88) (xy 262.89 55.88)
		)
		(stroke
			(width 0)
			(type default)
		)
	)
	(wire
		(pts
			(xy 110.49 71.12) (xy 127 71.12)
		)
		(stroke
			(width 0)
			(type default)
		)
	)
	(wire
		(pts
			(xy 106.68 208.28) (xy 113.03 208.28)
		)
		(stroke
			(width 0)
			(type default)
		)
	)
	(wire
		(pts
			(xy 299.72 194.31) (xy 299.72 196.85)
		)
		(stroke
			(width 0)
			(type default)
		)
	)
	(wire
		(pts
			(xy 322.58 100.33) (xy 322.58 108.585)
		)
		(stroke
			(width 0)
			(type default)
		)
	)
	(wire
		(pts
			(xy 344.17 45.72) (xy 363.22 45.72)
		)
		(stroke
			(width 0)
			(type default)
		)
	)
	(wire
		(pts
			(xy 318.77 53.34) (xy 339.09 53.34)
		)
		(stroke
			(width 0)
			(type default)
		)
	)
	(wire
		(pts
			(xy 271.78 114.3) (xy 271.78 116.84)
		)
		(stroke
			(width 0)
			(type default)
		)
	)
	(wire
		(pts
			(xy 299.72 196.85) (xy 302.26 196.85)
		)
		(stroke
			(width 0)
			(type default)
		)
	)
	(wire
		(pts
			(xy 340.36 200.66) (xy 340.36 203.2)
		)
		(stroke
			(width 0)
			(type default)
		)
	)
	(wire
		(pts
			(xy 302.26 124.46) (xy 318.77 124.46)
		)
		(stroke
			(width 0)
			(type default)
		)
	)
	(wire
		(pts
			(xy 30.48 269.24) (xy 33.02 269.24)
		)
		(stroke
			(width 0)
			(type default)
		)
	)
	(wire
		(pts
			(xy 340.36 208.28) (xy 341.63 208.28)
		)
		(stroke
			(width 0)
			(type default)
		)
	)
	(wire
		(pts
			(xy 106.68 226.06) (xy 113.03 226.06)
		)
		(stroke
			(width 0)
			(type default)
		)
	)
	(wire
		(pts
			(xy 184.15 191.77) (xy 184.15 189.23)
		)
		(stroke
			(width 0)
			(type default)
		)
	)
	(wire
		(pts
			(xy 190.5 101.6) (xy 196.85 101.6)
		)
		(stroke
			(width 0)
			(type default)
		)
	)
	(bus
		(pts
			(xy 364.49 46.99) (xy 364.49 52.07)
		)
		(stroke
			(width 0)
			(type default)
		)
	)
	(wire
		(pts
			(xy 340.36 210.82) (xy 340.36 213.36)
		)
		(stroke
			(width 0)
			(type default)
		)
	)
	(bus
		(pts
			(xy 245.11 62.23) (xy 245.11 67.31)
		)
		(stroke
			(width 0)
			(type default)
		)
	)
	(wire
		(pts
			(xy 196.85 93.98) (xy 196.85 96.52)
		)
		(stroke
			(width 0)
			(type default)
		)
	)
	(bus
		(pts
			(xy 245.11 67.31) (xy 245.11 69.85)
		)
		(stroke
			(width 0)
			(type default)
		)
	)
	(wire
		(pts
			(xy 281.94 185.42) (xy 299.72 185.42)
		)
		(stroke
			(width 0)
			(type default)
		)
	)
	(wire
		(pts
			(xy 106.68 236.22) (xy 113.03 236.22)
		)
		(stroke
			(width 0)
			(type default)
		)
	)
	(wire
		(pts
			(xy 397.51 200.66) (xy 400.05 200.66)
		)
		(stroke
			(width 0)
			(type default)
		)
	)
	(wire
		(pts
			(xy 397.51 208.28) (xy 400.05 208.28)
		)
		(stroke
			(width 0)
			(type default)
		)
	)
	(wire
		(pts
			(xy 327.66 83.82) (xy 330.2 83.82)
		)
		(stroke
			(width 0)
			(type default)
		)
	)
	(wire
		(pts
			(xy 113.03 248.92) (xy 113.03 251.46)
		)
		(stroke
			(width 0)
			(type default)
		)
	)
	(wire
		(pts
			(xy 246.38 60.96) (xy 262.89 60.96)
		)
		(stroke
			(width 0)
			(type default)
		)
	)
	(wire
		(pts
			(xy 196.85 96.52) (xy 196.85 101.6)
		)
		(stroke
			(width 0)
			(type default)
		)
	)
	(wire
		(pts
			(xy 229.87 97.79) (xy 229.87 78.74)
		)
		(stroke
			(width 0)
			(type default)
		)
	)
	(wire
		(pts
			(xy 318.77 60.96) (xy 339.09 60.96)
		)
		(stroke
			(width 0)
			(type default)
		)
	)
	(wire
		(pts
			(xy 302.26 119.38) (xy 322.58 119.38)
		)
		(stroke
			(width 0)
			(type default)
		)
	)
	(bus
		(pts
			(xy 139.7 208.28) (xy 137.16 210.82)
		)
		(stroke
			(width 0)
			(type default)
		)
	)
	(bus
		(pts
			(xy 71.12 81.28) (xy 69.85 80.01)
		)
		(stroke
			(width 0)
			(type default)
		)
	)
	(wire
		(pts
			(xy 322.58 119.38) (xy 322.58 111.125)
		)
		(stroke
			(width 0)
			(type default)
		)
	)
	(bus
		(pts
			(xy 71.12 44.45) (xy 71.12 46.99)
		)
		(stroke
			(width 0)
			(type default)
		)
	)
	(wire
		(pts
			(xy 269.24 124.46) (xy 269.24 128.27)
		)
		(stroke
			(width 0)
			(type default)
		)
	)
	(wire
		(pts
			(xy 318.77 63.5) (xy 341.63 63.5)
		)
		(stroke
			(width 0)
			(type default)
		)
	)
	(wire
		(pts
			(xy 309.88 190.5) (xy 309.88 196.85)
		)
		(stroke
			(width 0)
			(type default)
		)
	)
	(wire
		(pts
			(xy 113.03 208.28) (xy 113.03 203.2)
		)
		(stroke
			(width 0)
			(type default)
		)
	)
	(wire
		(pts
			(xy 97.79 254) (xy 127 254)
		)
		(stroke
			(width 0)
			(type default)
		)
	)
	(wire
		(pts
			(xy 269.24 184.15) (xy 269.24 186.69)
		)
		(stroke
			(width 0)
			(type default)
		)
	)
	(wire
		(pts
			(xy 30.48 208.28) (xy 33.02 208.28)
		)
		(stroke
			(width 0)
			(type default)
		)
	)
	(wire
		(pts
			(xy 299.72 185.42) (xy 302.26 185.42)
		)
		(stroke
			(width 0)
			(type default)
		)
	)
	(wire
		(pts
			(xy 309.88 185.42) (xy 309.88 190.5)
		)
		(stroke
			(width 0)
			(type default)
		)
	)
	(wire
		(pts
			(xy 261.62 107.95) (xy 271.78 107.95)
		)
		(stroke
			(width 0)
			(type default)
		)
	)
	(wire
		(pts
			(xy 243.84 128.27) (xy 243.84 129.54)
		)
		(stroke
			(width 0)
			(type default)
		)
	)
	(wire
		(pts
			(xy 127 254) (xy 129.54 254)
		)
		(stroke
			(width 0)
			(type default)
		)
	)
	(wire
		(pts
			(xy 73.66 76.2) (xy 100.33 76.2)
		)
		(stroke
			(width 0)
			(type default)
		)
	)
	(wire
		(pts
			(xy 106.68 256.54) (xy 113.03 256.54)
		)
		(stroke
			(width 0)
			(type default)
		)
	)
	(wire
		(pts
			(xy 397.51 203.2) (xy 400.05 203.2)
		)
		(stroke
			(width 0)
			(type default)
		)
	)
	(wire
		(pts
			(xy 119.38 220.98) (xy 119.38 243.84)
		)
		(stroke
			(width 0)
			(type default)
		)
	)
	(wire
		(pts
			(xy 340.36 210.82) (xy 341.63 210.82)
		)
		(stroke
			(width 0)
			(type default)
		)
	)
	(wire
		(pts
			(xy 97.79 256.54) (xy 101.6 256.54)
		)
		(stroke
			(width 0)
			(type default)
		)
	)
	(wire
		(pts
			(xy 72.39 71.12) (xy 105.41 71.12)
		)
		(stroke
			(width 0)
			(type default)
		)
	)
	(wire
		(pts
			(xy 246.38 45.72) (xy 262.89 45.72)
		)
		(stroke
			(width 0)
			(type default)
		)
	)
	(wire
		(pts
			(xy 113.03 226.06) (xy 113.03 223.52)
		)
		(stroke
			(width 0)
			(type default)
		)
	)
	(wire
		(pts
			(xy 227.33 100.33) (xy 227.33 76.2)
		)
		(stroke
			(width 0)
			(type default)
		)
	)
	(wire
		(pts
			(xy 72.39 63.5) (xy 105.41 63.5)
		)
		(stroke
			(width 0)
			(type default)
		)
	)
	(wire
		(pts
			(xy 105.41 76.2) (xy 127 76.2)
		)
		(stroke
			(width 0)
			(type default)
		)
	)
	(wire
		(pts
			(xy 330.2 83.82) (xy 330.2 85.09)
		)
		(stroke
			(width 0)
			(type default)
		)
	)
	(bus
		(pts
			(xy 68.58 80.01) (xy 69.85 80.01)
		)
		(stroke
			(width 0)
			(type default)
		)
	)
	(bus
		(pts
			(xy 71.12 81.28) (xy 71.12 83.82)
		)
		(stroke
			(width 0)
			(type default)
		)
	)
	(wire
		(pts
			(xy 97.79 203.2) (xy 101.6 203.2)
		)
		(stroke
			(width 0)
			(type default)
		)
	)
	(wire
		(pts
			(xy 102.87 93.98) (xy 127 93.98)
		)
		(stroke
			(width 0)
			(type default)
		)
	)
	(wire
		(pts
			(xy 30.48 264.16) (xy 33.02 264.16)
		)
		(stroke
			(width 0)
			(type default)
		)
	)
	(bus
		(pts
			(xy 245.11 54.61) (xy 245.11 59.69)
		)
		(stroke
			(width 0)
			(type default)
		)
	)
	(wire
		(pts
			(xy 190.5 96.52) (xy 196.85 96.52)
		)
		(stroke
			(width 0)
			(type default)
		)
	)
	(bus
		(pts
			(xy 245.11 52.07) (xy 245.11 54.61)
		)
		(stroke
			(width 0)
			(type default)
		)
	)
	(wire
		(pts
			(xy 195.58 209.55) (xy 198.12 209.55)
		)
		(stroke
			(width 0)
			(type default)
		)
	)
	(bus
		(pts
			(xy 364.49 54.61) (xy 364.49 59.69)
		)
		(stroke
			(width 0)
			(type default)
		)
	)
	(bus
		(pts
			(xy 364.49 52.07) (xy 364.49 54.61)
		)
		(stroke
			(width 0)
			(type default)
		)
	)
	(wire
		(pts
			(xy 97.79 246.38) (xy 101.6 246.38)
		)
		(stroke
			(width 0)
			(type default)
		)
	)
	(wire
		(pts
			(xy 271.78 107.95) (xy 276.86 107.95)
		)
		(stroke
			(width 0)
			(type default)
		)
	)
	(bus
		(pts
			(xy 71.12 52.07) (xy 71.12 54.61)
		)
		(stroke
			(width 0)
			(type default)
		)
	)
	(wire
		(pts
			(xy 110.49 63.5) (xy 127 63.5)
		)
		(stroke
			(width 0)
			(type default)
		)
	)
	(bus
		(pts
			(xy 71.12 46.99) (xy 71.12 52.07)
		)
		(stroke
			(width 0)
			(type default)
		)
	)
	(bus
		(pts
			(xy 139.7 208.28) (xy 142.24 208.28)
		)
		(stroke
			(width 0)
			(type default)
		)
	)
	(bus
		(pts
			(xy 71.12 62.23) (xy 71.12 67.31)
		)
		(stroke
			(width 0)
			(type default)
		)
	)
	(bus
		(pts
			(xy 283.21 205.74) (xy 283.21 208.28)
		)
		(stroke
			(width 0)
			(type default)
		)
	)
	(bus
		(pts
			(xy 245.11 46.99) (xy 245.11 52.07)
		)
		(stroke
			(width 0)
			(type default)
		)
	)
	(wire
		(pts
			(xy 38.1 261.62) (xy 41.91 261.62)
		)
		(stroke
			(width 0)
			(type default)
		)
	)
	(wire
		(pts
			(xy 127 252.73) (xy 127 254)
		)
		(stroke
			(width 0)
			(type default)
		)
	)
	(wire
		(pts
			(xy 119.38 220.98) (xy 135.89 220.98)
		)
		(stroke
			(width 0)
			(type default)
		)
	)
	(wire
		(pts
			(xy 336.55 78.74) (xy 336.55 80.01)
		)
		(stroke
			(width 0)
			(type default)
		)
	)
	(wire
		(pts
			(xy 106.68 203.2) (xy 113.03 203.2)
		)
		(stroke
			(width 0)
			(type default)
		)
	)
	(wire
		(pts
			(xy 97.79 243.84) (xy 119.38 243.84)
		)
		(stroke
			(width 0)
			(type default)
		)
	)
	(wire
		(pts
			(xy 106.68 102.87) (xy 106.68 105.41)
		)
		(stroke
			(width 0)
			(type default)
		)
	)
	(bus
		(pts
			(xy 283.21 200.66) (xy 285.75 200.66)
		)
		(stroke
			(width 0)
			(type default)
		)
	)
	(wire
		(pts
			(xy 195.58 205.74) (xy 195.58 209.55)
		)
		(stroke
			(width 0)
			(type default)
		)
	)
	(bus
		(pts
			(xy 71.12 59.69) (xy 71.12 62.23)
		)
		(stroke
			(width 0)
			(type default)
		)
	)
	(wire
		(pts
			(xy 38.1 203.2) (xy 41.91 203.2)
		)
		(stroke
			(width 0)
			(type default)
		)
	)
	(wire
		(pts
			(xy 73.66 93.98) (xy 102.87 93.98)
		)
		(stroke
			(width 0)
			(type default)
		)
	)
	(wire
		(pts
			(xy 281.94 194.31) (xy 281.94 185.42)
		)
		(stroke
			(width 0)
			(type default)
		)
	)
	(wire
		(pts
			(xy 73.66 91.44) (xy 106.68 91.44)
		)
		(stroke
			(width 0)
			(type default)
		)
	)
	(wire
		(pts
			(xy 97.79 208.28) (xy 101.6 208.28)
		)
		(stroke
			(width 0)
			(type default)
		)
	)
	(wire
		(pts
			(xy 30.48 264.16) (xy 30.48 261.62)
		)
		(stroke
			(width 0)
			(type default)
		)
	)
	(wire
		(pts
			(xy 246.38 53.34) (xy 262.89 53.34)
		)
		(stroke
			(width 0)
			(type default)
		)
	)
	(wire
		(pts
			(xy 184.15 189.23) (xy 189.23 189.23)
		)
		(stroke
			(width 0)
			(type default)
		)
	)
	(wire
		(pts
			(xy 302.26 121.92) (xy 325.12 121.92)
		)
		(stroke
			(width 0)
			(type default)
		)
	)
	(wire
		(pts
			(xy 113.03 228.6) (xy 113.03 226.06)
		)
		(stroke
			(width 0)
			(type default)
		)
	)
	(wire
		(pts
			(xy 116.84 101.6) (xy 119.38 101.6)
		)
		(stroke
			(width 0)
			(type default)
		)
	)
	(wire
		(pts
			(xy 318.77 45.72) (xy 339.09 45.72)
		)
		(stroke
			(width 0)
			(type default)
		)
	)
	(wire
		(pts
			(xy 123.19 96.52) (xy 127 96.52)
		)
		(stroke
			(width 0)
			(type default)
		)
	)
	(bus
		(pts
			(xy 68.58 40.64) (xy 71.12 43.18)
		)
		(stroke
			(width 0)
			(type default)
		)
	)
	(wire
		(pts
			(xy 105.41 68.58) (xy 127 68.58)
		)
		(stroke
			(width 0)
			(type default)
		)
	)
	(wire
		(pts
			(xy 110.49 78.74) (xy 127 78.74)
		)
		(stroke
			(width 0)
			(type default)
		)
	)
	(bus
		(pts
			(xy 71.12 73.66) (xy 71.12 76.2)
		)
		(stroke
			(width 0)
			(type default)
		)
	)
	(wire
		(pts
			(xy 340.36 203.2) (xy 341.63 203.2)
		)
		(stroke
			(width 0)
			(type default)
		)
	)
	(wire
		(pts
			(xy 30.48 256.54) (xy 30.48 261.62)
		)
		(stroke
			(width 0)
			(type default)
		)
	)
	(wire
		(pts
			(xy 184.15 186.69) (xy 189.23 186.69)
		)
		(stroke
			(width 0)
			(type default)
		)
	)
	(wire
		(pts
			(xy 113.03 256.54) (xy 113.03 259.08)
		)
		(stroke
			(width 0)
			(type default)
		)
	)
	(wire
		(pts
			(xy 73.66 86.36) (xy 127 86.36)
		)
		(stroke
			(width 0)
			(type default)
		)
	)
	(bus
		(pts
			(xy 71.12 88.9) (xy 71.12 91.44)
		)
		(stroke
			(width 0)
			(type default)
		)
	)
	(bus
		(pts
			(xy 245.11 59.69) (xy 245.11 62.23)
		)
		(stroke
			(width 0)
			(type default)
		)
	)
	(wire
		(pts
			(xy 182.88 101.6) (xy 185.42 101.6)
		)
		(stroke
			(width 0)
			(type default)
		)
	)
	(wire
		(pts
			(xy 276.86 127) (xy 276.86 129.54)
		)
		(stroke
			(width 0)
			(type default)
		)
	)
	(wire
		(pts
			(xy 106.68 231.14) (xy 113.03 231.14)
		)
		(stroke
			(width 0)
			(type default)
		)
	)
	(wire
		(pts
			(xy 400.05 200.66) (xy 400.05 203.2)
		)
		(stroke
			(width 0)
			(type default)
		)
	)
	(wire
		(pts
			(xy 106.68 223.52) (xy 113.03 223.52)
		)
		(stroke
			(width 0)
			(type default)
		)
	)
	(wire
		(pts
			(xy 194.31 186.69) (xy 198.12 186.69)
		)
		(stroke
			(width 0)
			(type default)
		)
	)
	(bus
		(pts
			(xy 283.21 200.66) (xy 283.21 203.2)
		)
		(stroke
			(width 0)
			(type default)
		)
	)
	(wire
		(pts
			(xy 97.79 218.44) (xy 135.89 218.44)
		)
		(stroke
			(width 0)
			(type default)
		)
	)
	(bus
		(pts
			(xy 245.11 35.56) (xy 245.11 44.45)
		)
		(stroke
			(width 0)
			(type default)
		)
	)
	(wire
		(pts
			(xy 116.84 102.87) (xy 116.84 101.6)
		)
		(stroke
			(width 0)
			(type default)
		)
	)
	(bus
		(pts
			(xy 71.12 88.9) (xy 69.85 87.63)
		)
		(stroke
			(width 0)
			(type default)
		)
	)
	(bus
		(pts
			(xy 364.49 44.45) (xy 364.49 46.99)
		)
		(stroke
			(width 0)
			(type default)
		)
	)
	(polyline
		(pts
			(xy 210.82 22.86) (xy 210.82 137.16)
		)
		(stroke
			(width 0)
			(type default)
		)
	)
	(wire
		(pts
			(xy 194.31 191.77) (xy 198.12 191.77)
		)
		(stroke
			(width 0)
			(type default)
		)
	)
	(wire
		(pts
			(xy 30.48 269.24) (xy 30.48 264.16)
		)
		(stroke
			(width 0)
			(type default)
		)
	)
	(wire
		(pts
			(xy 252.73 85.09) (xy 254 85.09)
		)
		(stroke
			(width 0)
			(type default)
		)
	)
	(wire
		(pts
			(xy 184.15 184.15) (xy 189.23 184.15)
		)
		(stroke
			(width 0)
			(type default)
		)
	)
	(wire
		(pts
			(xy 30.48 210.82) (xy 33.02 210.82)
		)
		(stroke
			(width 0)
			(type default)
		)
	)
	(wire
		(pts
			(xy 260.35 83.82) (xy 262.89 83.82)
		)
		(stroke
			(width 0)
			(type default)
		)
	)
	(wire
		(pts
			(xy 30.48 261.62) (xy 33.02 261.62)
		)
		(stroke
			(width 0)
			(type default)
		)
	)
	(wire
		(pts
			(xy 254 127) (xy 254 128.27)
		)
		(stroke
			(width 0)
			(type default)
		)
	)
	(wire
		(pts
			(xy 251.46 118.11) (xy 254 118.11)
		)
		(stroke
			(width 0)
			(type default)
		)
	)
	(wire
		(pts
			(xy 302.26 127) (xy 318.77 127)
		)
		(stroke
			(width 0)
			(type default)
		)
	)
	(wire
		(pts
			(xy 106.68 91.44) (xy 127 91.44)
		)
		(stroke
			(width 0)
			(type default)
		)
	)
	(wire
		(pts
			(xy 325.12 108.585) (xy 325.12 97.79)
		)
		(stroke
			(width 0)
			(type default)
		)
	)
	(wire
		(pts
			(xy 340.36 208.28) (xy 340.36 210.82)
		)
		(stroke
			(width 0)
			(type default)
		)
	)
	(wire
		(pts
			(xy 254 204.47) (xy 281.94 204.47)
		)
		(stroke
			(width 0)
			(type default)
		)
	)
	(wire
		(pts
			(xy 322.58 111.125) (xy 325.12 108.585)
		)
		(stroke
			(width 0)
			(type default)
		)
	)
	(wire
		(pts
			(xy 97.79 233.68) (xy 101.6 233.68)
		)
		(stroke
			(width 0)
			(type default)
		)
	)
	(wire
		(pts
			(xy 318.77 71.12) (xy 341.63 71.12)
		)
		(stroke
			(width 0)
			(type default)
		)
	)
	(wire
		(pts
			(xy 72.39 55.88) (xy 127 55.88)
		)
		(stroke
			(width 0)
			(type default)
		)
	)
	(wire
		(pts
			(xy 344.17 68.58) (xy 363.22 68.58)
		)
		(stroke
			(width 0)
			(type default)
		)
	)
	(wire
		(pts
			(xy 182.88 91.44) (xy 185.42 91.44)
		)
		(stroke
			(width 0)
			(type default)
		)
	)
	(wire
		(pts
			(xy 72.39 45.72) (xy 127 45.72)
		)
		(stroke
			(width 0)
			(type default)
		)
	)
	(wire
		(pts
			(xy 106.68 248.92) (xy 113.03 248.92)
		)
		(stroke
			(width 0)
			(type default)
		)
	)
	(wire
		(pts
			(xy 318.77 83.82) (xy 322.58 83.82)
		)
		(stroke
			(width 0)
			(type default)
		)
	)
	(wire
		(pts
			(xy 251.46 128.27) (xy 254 128.27)
		)
		(stroke
			(width 0)
			(type default)
		)
	)
	(wire
		(pts
			(xy 113.03 233.68) (xy 113.03 231.14)
		)
		(stroke
			(width 0)
			(type default)
		)
	)
	(bus
		(pts
			(xy 321.31 130.81) (xy 320.04 129.54)
		)
		(stroke
			(width 0)
			(type default)
		)
	)
	(wire
		(pts
			(xy 190.5 91.44) (xy 196.85 91.44)
		)
		(stroke
			(width 0)
			(type default)
		)
	)
	(wire
		(pts
			(xy 72.39 60.96) (xy 100.33 60.96)
		)
		(stroke
			(width 0)
			(type default)
		)
	)
	(bus
		(pts
			(xy 67.31 40.64) (xy 68.58 40.64)
		)
		(stroke
			(width 0)
			(type default)
		)
	)
	(wire
		(pts
			(xy 194.31 184.15) (xy 198.12 184.15)
		)
		(stroke
			(width 0)
			(type default)
		)
	)
	(wire
		(pts
			(xy 261.62 106.68) (xy 261.62 107.95)
		)
		(stroke
			(width 0)
			(type default)
		)
	)
	(bus
		(pts
			(xy 137.16 210.82) (xy 137.16 214.63)
		)
		(stroke
			(width 0)
			(type default)
		)
	)
	(bus
		(pts
			(xy 246.38 34.29) (xy 245.11 35.56)
		)
		(stroke
			(width 0)
			(type default)
		)
	)
	(wire
		(pts
			(xy 278.13 127) (xy 276.86 127)
		)
		(stroke
			(width 0)
			(type default)
		)
	)
	(wire
		(pts
			(xy 30.48 212.09) (xy 30.48 210.82)
		)
		(stroke
			(width 0)
			(type default)
		)
	)
	(wire
		(pts
			(xy 195.58 196.85) (xy 198.12 196.85)
		)
		(stroke
			(width 0)
			(type default)
		)
	)
	(wire
		(pts
			(xy 262.89 186.69) (xy 269.24 186.69)
		)
		(stroke
			(width 0)
			(type default)
		)
	)
	(wire
		(pts
			(xy 254 207.01) (xy 281.94 207.01)
		)
		(stroke
			(width 0)
			(type default)
		)
	)
	(wire
		(pts
			(xy 106.68 228.6) (xy 113.03 228.6)
		)
		(stroke
			(width 0)
			(type default)
		)
	)
	(wire
		(pts
			(xy 325.12 97.79) (xy 229.87 97.79)
		)
		(stroke
			(width 0)
			(type default)
		)
	)
	(wire
		(pts
			(xy 97.79 248.92) (xy 101.6 248.92)
		)
		(stroke
			(width 0)
			(type default)
		)
	)
	(bus
		(pts
			(xy 364.49 62.23) (xy 364.49 67.31)
		)
		(stroke
			(width 0)
			(type default)
		)
	)
	(wire
		(pts
			(xy 127 245.11) (xy 127 246.38)
		)
		(stroke
			(width 0)
			(type default)
		)
	)
	(wire
		(pts
			(xy 243.84 128.27) (xy 246.38 128.27)
		)
		(stroke
			(width 0)
			(type default)
		)
	)
	(wire
		(pts
			(xy 72.39 68.58) (xy 100.33 68.58)
		)
		(stroke
			(width 0)
			(type default)
		)
	)
	(label "PCIex4.TX0+"
		(at 246.38 45.72 0)
		(effects
			(font
				(size 1.27 1.27)
			)
			(justify left bottom)
		)
	)
	(label "PCIE_CLK_JHL_P"
		(at 318.77 121.92 180)
		(effects
			(font
				(size 1.27 1.27)
			)
			(justify right bottom)
		)
	)
	(label "USB3.TX0_P"
		(at 86.36 60.96 180)
		(effects
			(font
				(size 1.27 1.27)
			)
			(justify right bottom)
		)
	)
	(label "USB3.RX0_P"
		(at 86.36 45.72 180)
		(effects
			(font
				(size 1.27 1.27)
			)
			(justify right bottom)
		)
	)
	(label "TB_PCIE_TX2_P"
		(at 320.04 60.96 0)
		(effects
			(font
				(size 1.27 1.27)
			)
			(justify left bottom)
		)
	)
	(label "I2C1.SDA"
		(at 123.19 215.9 0)
		(effects
			(font
				(size 1.27 1.27)
			)
			(justify left bottom)
		)
	)
	(label "XTAL_25_IN"
		(at 254 194.31 0)
		(effects
			(font
				(size 1.27 1.27)
			)
			(justify left bottom)
		)
	)
	(label "PCIex4.RX2+"
		(at 363.22 60.96 180)
		(effects
			(font
				(size 1.27 1.27)
			)
			(justify right bottom)
		)
	)
	(label "I2C1.IRQ"
		(at 123.19 220.98 0)
		(effects
			(font
				(size 1.27 1.27)
			)
			(justify left bottom)
		)
	)
	(label "USB_RP.D+"
		(at 85.09 83.82 180)
		(effects
			(font
				(size 1.27 1.27)
			)
			(justify right bottom)
		)
	)
	(label "PCIex4.TX1+"
		(at 246.38 53.34 0)
		(effects
			(font
				(size 1.27 1.27)
			)
			(justify left bottom)
		)
	)
	(label "TB_FLASH.MISO"
		(at 255.27 204.47 0)
		(effects
			(font
				(size 1.27 1.27)
			)
			(justify left bottom)
		)
	)
	(label "PA_TX0_N"
		(at 115.57 63.5 0)
		(effects
			(font
				(size 1.27 1.27)
			)
			(justify left bottom)
		)
	)
	(label "TB_PCIE_TX2_N"
		(at 320.04 63.5 0)
		(effects
			(font
				(size 1.27 1.27)
			)
			(justify left bottom)
		)
	)
	(label "PA_TX1_N"
		(at 115.57 71.12 0)
		(effects
			(font
				(size 1.27 1.27)
			)
			(justify left bottom)
		)
	)
	(label "PCIex4.RX3-"
		(at 363.22 71.12 180)
		(effects
			(font
				(size 1.27 1.27)
			)
			(justify right bottom)
		)
	)
	(label "PCIex4.TX2+"
		(at 246.38 60.96 0)
		(effects
			(font
				(size 1.27 1.27)
			)
			(justify left bottom)
		)
	)
	(label "TB_FLASH.MOSI"
		(at 255.27 201.93 0)
		(effects
			(font
				(size 1.27 1.27)
			)
			(justify left bottom)
		)
	)
	(label "PCIex4.TX3+"
		(at 246.38 68.58 0)
		(effects
			(font
				(size 1.27 1.27)
			)
			(justify left bottom)
		)
	)
	(label "PA_AUX_P"
		(at 115.57 76.2 0)
		(effects
			(font
				(size 1.27 1.27)
			)
			(justify left bottom)
		)
	)
	(label "LSX_1.LSX_P2R"
		(at 76.2 93.98 0)
		(effects
			(font
				(size 1.27 1.27)
			)
			(justify left bottom)
		)
	)
	(label "USB3.RX1_N"
		(at 86.36 55.88 180)
		(effects
			(font
				(size 1.27 1.27)
			)
			(justify right bottom)
		)
	)
	(label "TB_PCIE_TX3_P"
		(at 320.04 68.58 0)
		(effects
			(font
				(size 1.27 1.27)
			)
			(justify left bottom)
		)
	)
	(label "TB_PCIE_TX1_N"
		(at 320.04 55.88 0)
		(effects
			(font
				(size 1.27 1.27)
			)
			(justify left bottom)
		)
	)
	(label "I2C1.SCL"
		(at 123.19 218.44 0)
		(effects
			(font
				(size 1.27 1.27)
			)
			(justify left bottom)
		)
	)
	(label "USB3.TX1_N"
		(at 86.36 71.12 180)
		(effects
			(font
				(size 1.27 1.27)
			)
			(justify right bottom)
		)
	)
	(label "USB3.TX0_N"
		(at 86.36 63.5 180)
		(effects
			(font
				(size 1.27 1.27)
			)
			(justify right bottom)
		)
	)
	(label "REFCLK.+"
		(at 318.77 127 180)
		(effects
			(font
				(size 1.27 1.27)
			)
			(justify right bottom)
		)
	)
	(label "REFCLK.-"
		(at 318.77 124.46 180)
		(effects
			(font
				(size 1.27 1.27)
			)
			(justify right bottom)
		)
	)
	(label "PA_AUX_N"
		(at 115.57 78.74 0)
		(effects
			(font
				(size 1.27 1.27)
			)
			(justify left bottom)
		)
	)
	(label "LSX_1.LSX_R2P"
		(at 76.2 91.44 0)
		(effects
			(font
				(size 1.27 1.27)
			)
			(justify left bottom)
		)
	)
	(label "PCIex4.RX1-"
		(at 363.22 55.88 180)
		(effects
			(font
				(size 1.27 1.27)
			)
			(justify right bottom)
		)
	)
	(label "TB_PCIE_TX0_P"
		(at 320.04 45.72 0)
		(effects
			(font
				(size 1.27 1.27)
			)
			(justify left bottom)
		)
	)
	(label "XTAL_25_OUT"
		(at 254 196.85 0)
		(effects
			(font
				(size 1.27 1.27)
			)
			(justify left bottom)
		)
	)
	(label "TB_PCIE_TX0_N"
		(at 320.04 48.26 0)
		(effects
			(font
				(size 1.27 1.27)
			)
			(justify left bottom)
		)
	)
	(label "USB_RP.D-"
		(at 85.09 86.36 180)
		(effects
			(font
				(size 1.27 1.27)
			)
			(justify right bottom)
		)
	)
	(label "PCIE_CLK_JHL_N"
		(at 318.77 119.38 180)
		(effects
			(font
				(size 1.27 1.27)
			)
			(justify right bottom)
		)
	)
	(label "PA_TX0_P"
		(at 115.57 60.96 0)
		(effects
			(font
				(size 1.27 1.27)
			)
			(justify left bottom)
		)
	)
	(label "TB_FLASH.CLK"
		(at 255.27 209.55 0)
		(effects
			(font
				(size 1.27 1.27)
			)
			(justify left bottom)
		)
	)
	(label "PCIex4.RX0-"
		(at 363.22 48.26 180)
		(effects
			(font
				(size 1.27 1.27)
			)
			(justify right bottom)
		)
	)
	(label "TB_PCIE_TX1_P"
		(at 320.04 53.34 0)
		(effects
			(font
				(size 1.27 1.27)
			)
			(justify left bottom)
		)
	)
	(label "USB3.TX1_P"
		(at 86.36 68.58 180)
		(effects
			(font
				(size 1.27 1.27)
			)
			(justify right bottom)
		)
	)
	(label "PCIE_CLK_JHL_N"
		(at 246.38 78.74 0)
		(effects
			(font
				(size 1.27 1.27)
			)
			(justify left bottom)
		)
	)
	(label "PCIex4.RX3+"
		(at 363.22 68.58 180)
		(effects
			(font
				(size 1.27 1.27)
			)
			(justify right bottom)
		)
	)
	(label "USB3.RX1_P"
		(at 86.36 53.34 180)
		(effects
			(font
				(size 1.27 1.27)
			)
			(justify right bottom)
		)
	)
	(label "AUX.-"
		(at 80.01 78.74 180)
		(effects
			(font
				(size 1.27 1.27)
			)
			(justify right bottom)
		)
	)
	(label "PCIex4.RX0+"
		(at 363.22 45.72 180)
		(effects
			(font
				(size 1.27 1.27)
			)
			(justify right bottom)
		)
	)
	(label "PCIex4.TX3-"
		(at 246.38 71.12 0)
		(effects
			(font
				(size 1.27 1.27)
			)
			(justify left bottom)
		)
	)
	(label "PCIE_CLK_JHL_P"
		(at 246.38 76.2 0)
		(effects
			(font
				(size 1.27 1.27)
			)
			(justify left bottom)
		)
	)
	(label "AUX.+"
		(at 80.01 76.2 180)
		(effects
			(font
				(size 1.27 1.27)
			)
			(justify right bottom)
		)
	)
	(label "PCIex4.RX2-"
		(at 363.22 63.5 180)
		(effects
			(font
				(size 1.27 1.27)
			)
			(justify right bottom)
		)
	)
	(label "PCIex4.RX1+"
		(at 363.22 53.34 180)
		(effects
			(font
				(size 1.27 1.27)
			)
			(justify right bottom)
		)
	)
	(label "PCIex4.TX1-"
		(at 246.38 55.88 0)
		(effects
			(font
				(size 1.27 1.27)
			)
			(justify left bottom)
		)
	)
	(label "USB3.RX0_N"
		(at 86.36 48.26 180)
		(effects
			(font
				(size 1.27 1.27)
			)
			(justify right bottom)
		)
	)
	(label "TB_PCIE_TX3_N"
		(at 320.04 71.12 0)
		(effects
			(font
				(size 1.27 1.27)
			)
			(justify left bottom)
		)
	)
	(label "TB_FLASH.~{CE}"
		(at 255.27 207.01 0)
		(effects
			(font
				(size 1.27 1.27)
			)
			(justify left bottom)
		)
	)
	(label "PCIex4.TX0-"
		(at 246.38 48.26 0)
		(effects
			(font
				(size 1.27 1.27)
			)
			(justify left bottom)
		)
	)
	(label "PCIex4.TX2-"
		(at 246.38 63.5 0)
		(effects
			(font
				(size 1.27 1.27)
			)
			(justify left bottom)
		)
	)
	(label "PA_TX1_P"
		(at 115.57 68.58 0)
		(effects
			(font
				(size 1.27 1.27)
			)
			(justify left bottom)
		)
	)
	(hierarchical_label "USB_RP{USB}"
		(shape bidirectional)
		(at 68.58 80.01 180)
		(effects
			(font
				(size 1.27 1.27)
			)
			(justify right)
		)
	)
	(hierarchical_label "REFCLK{CLK}"
		(shape output)
		(at 323.85 130.81 0)
		(effects
			(font
				(size 1.27 1.27)
			)
			(justify left)
		)
	)
	(hierarchical_label "RESET_N"
		(shape input)
		(at 255.27 189.23 0)
		(effects
			(font
				(size 1.27 1.27)
			)
			(justify left)
		)
	)
	(hierarchical_label "FLASH_WP"
		(shape output)
		(at 101.6 219.71 0)
		(effects
			(font
				(size 1.27 1.27)
			)
			(justify left)
		)
	)
	(hierarchical_label "TB_FLASH{SPI}"
		(shape bidirectional)
		(at 285.75 200.66 0)
		(effects
			(font
				(size 1.27 1.27)
			)
			(justify left)
		)
	)
	(hierarchical_label "USB3{USB_3.0}"
		(shape bidirectional)
		(at 67.31 40.64 180)
		(effects
			(font
				(size 1.27 1.27)
			)
			(justify right)
		)
	)
	(hierarchical_label "HPD"
		(shape input)
		(at 123.19 96.52 180)
		(effects
			(font
				(size 1.27 1.27)
			)
			(justify right)
		)
	)
	(hierarchical_label "~{PE_RST}"
		(shape output)
		(at 341.63 78.74 0)
		(effects
			(font
				(size 1.27 1.27)
			)
			(justify left)
		)
	)
	(hierarchical_label "LSX_1{LSX}"
		(shape bidirectional)
		(at 68.58 87.63 180)
		(effects
			(font
				(size 1.27 1.27)
			)
			(justify right)
		)
	)
	(hierarchical_label "PCIex4{PCIe}"
		(shape bidirectional)
		(at 374.65 34.29 0)
		(effects
			(font
				(size 1.27 1.27)
			)
			(justify left)
		)
	)
	(hierarchical_label "~{PE_WAKE}"
		(shape input)
		(at 129.54 254 0)
		(effects
			(font
				(size 1.27 1.27)
			)
			(justify left)
		)
	)
	(hierarchical_label "I2C1{I2C}"
		(shape bidirectional)
		(at 142.24 208.28 0)
		(effects
			(font
				(size 1.27 1.27)
			)
			(justify left)
		)
	)
	(hierarchical_label "AUX{AUX_TB}"
		(shape bidirectional)
		(at 67.31 71.12 180)
		(effects
			(font
				(size 1.27 1.27)
			)
			(justify right)
		)
	)
	(rule_area
		(polyline
			(pts
				(xy 302.895 114.3) (xy 339.09 114.3) (xy 339.09 133.35) (xy 302.895 133.35)
			)
			(stroke
				(width 0)
				(type dash)
			)
			(fill
				(type none)
			)
		)
	)
	(rule_area
		(polyline
			(pts
				(xy 125.73 57.15) (xy 114.3 57.15) (xy 114.3 80.01) (xy 125.73 80.01)
			)
			(stroke
				(width 0)
				(type dash)
			)
			(fill
				(type none)
			)
		)
	)
	(rule_area
		(polyline
			(pts
				(xy 318.77 41.91) (xy 335.28 41.91) (xy 335.28 73.66) (xy 318.77 73.66)
			)
			(stroke
				(width 0)
				(type dash)
			)
			(fill
				(type none)
			)
		)
	)
	(netclass_flag ""
		(length 2.54)
		(shape round)
		(at 114.3 57.15 90)
		(effects
			(font
				(size 1.27 1.27)
			)
			(justify left bottom)
		)
		(property "Netclass" "85Ohm-diff_USB4"
			(at 110.49 57.15 0)
			(effects
				(font
					(size 1.27 1.27)
				)
				(justify right)
			)
		)
		(property "Component Class" ""
			(at -109.22 3.81 0)
			(effects
				(font
					(size 1.27 1.27)
					(italic yes)
				)
				(justify right)
			)
		)
	)
	(netclass_flag ""
		(length 2.54)
		(shape round)
		(at 339.09 114.3 270)
		(effects
			(font
				(size 1.27 1.27)
			)
			(justify right bottom)
		)
		(property "Netclass" "85Ohm-diff_PCIe"
			(at 342.9 114.3 0)
			(effects
				(font
					(size 1.27 1.27)
				)
				(justify left)
			)
		)
		(property "Component Class" ""
			(at 115.57 60.96 0)
			(effects
				(font
					(size 1.27 1.27)
					(italic yes)
				)
				(justify right)
			)
		)
	)
	(netclass_flag ""
		(length 2.54)
		(shape round)
		(at 335.28 41.91 0)
		(fields_autoplaced yes)
		(effects
			(font
				(size 1.27 1.27)
			)
			(justify left bottom)
		)
		(property "Netclass" "85Ohm-diff_PCIe"
			(at 334.5815 39.37 0)
			(effects
				(font
					(size 1.27 1.27)
				)
				(justify right)
			)
		)
		(property "Component Class" ""
			(at 111.76 -11.43 0)
			(effects
				(font
					(size 1.27 1.27)
					(italic yes)
				)
				(justify right)
			)
		)
	)
	(symbol
		(lib_id "antmicropower:GND")
		(at 336.55 85.09 0)
		(unit 1)
		(exclude_from_sim no)
		(in_bom yes)
		(on_board yes)
		(dnp no)
		(property "Reference" "#PWR077"
			(at 336.55 91.44 0)
			(effects
				(font
					(size 1.27 1.27)
				)
				(hide yes)
			)
		)
		(property "Value" "GND"
			(at 336.55 88.9 0)
			(effects
				(font
					(size 1.27 1.27)
				)
			)
		)
		(property "Footprint" ""
			(at 336.55 85.09 0)
			(effects
				(font
					(size 1.27 1.27)
				)
				(hide yes)
			)
		)
		(property "Datasheet" ""
			(at 336.55 85.09 0)
			(effects
				(font
					(size 1.27 1.27)
				)
				(hide yes)
			)
		)
		(property "Description" ""
			(at 336.55 85.09 0)
			(effects
				(font
					(size 1.27 1.27)
				)
				(hide yes)
			)
		)
		(property "Author" "Antmicro"
			(at 345.44 92.71 0)
			(effects
				(font
					(size 1.27 1.27)
					(thickness 0.15)
				)
				(justify left bottom)
				(hide yes)
			)
		)
		(property "License" "Apache-2.0"
			(at 345.44 95.25 0)
			(effects
				(font
					(size 1.27 1.27)
					(thickness 0.15)
				)
				(justify left bottom)
				(hide yes)
			)
		)
		(pin "1"
		)
		(instances
			(project "thunderbolt-to-10gbe-adapter"
				(path ""
					(reference "#PWR077")
					(unit 1)
				)
			)
		)
	)
	(symbol
		(lib_id "antmicroCapacitors0402:C_220n_0402")
		(at 100.33 60.96 0)
		(unit 1)
		(exclude_from_sim no)
		(in_bom yes)
		(on_board yes)
		(dnp no)
		(property "Reference" "C33"
			(at 100.076 59.69 0)
			(effects
				(font
					(size 1.27 1.27)
					(thickness 0.15)
				)
			)
		)
		(property "Value" "C_220n_0402"
			(at 120.65 71.12 0)
			(effects
				(font
					(size 1.27 1.27)
					(thickness 0.15)
				)
				(justify left bottom)
				(hide yes)
			)
		)
		(property "Footprint" "antmicro-footprints:C_0402_1005Metric"
			(at 120.65 73.66 0)
			(effects
				(font
					(size 1.27 1.27)
					(thickness 0.15)
				)
				(justify left bottom)
				(hide yes)
			)
		)
		(property "Datasheet" "https://www.yageo.com/en/Chart/Download/pdf/CC0402KRX5R6BB224"
			(at 120.65 76.2 0)
			(effects
				(font
					(size 1.27 1.27)
					(thickness 0.15)
				)
				(justify left bottom)
				(hide yes)
			)
		)
		(property "Description" "SMD Multilayer Ceramic Capacitor, 0.22 µF, 10 V, 0402 [1005 Metric], ± 10%, X5R, CC Series"
			(at 100.33 60.96 0)
			(effects
				(font
					(size 1.27 1.27)
				)
				(hide yes)
			)
		)
		(property "MPN" "CC0402KRX5R6BB224"
			(at 120.65 78.74 0)
			(effects
				(font
					(size 1.27 1.27)
					(thickness 0.15)
				)
				(justify left bottom)
				(hide yes)
			)
		)
		(property "Manufacturer" "YAGEO"
			(at 120.65 81.28 0)
			(effects
				(font
					(size 1.27 1.27)
					(thickness 0.15)
				)
				(justify left bottom)
				(hide yes)
			)
		)
		(property "License" "Apache-2.0"
			(at 120.65 83.82 0)
			(effects
				(font
					(size 1.27 1.27)
					(thickness 0.15)
				)
				(justify left bottom)
				(hide yes)
			)
		)
		(property "Author" "Antmicro"
			(at 120.65 86.36 0)
			(effects
				(font
					(size 1.27 1.27)
					(thickness 0.15)
				)
				(justify left bottom)
				(hide yes)
			)
		)
		(property "Val" "220n"
			(at 99.568 62.484 0)
			(effects
				(font
					(size 1.27 1.27)
					(thickness 0.15)
				)
			)
		)
		(property "Voltage" ""
			(at 120.65 88.9 0)
			(effects
				(font
					(size 1.27 1.27)
				)
				(justify left bottom)
				(hide yes)
			)
		)
		(property "Dielectric" ""
			(at 120.65 91.44 0)
			(effects
				(font
					(size 1.27 1.27)
				)
				(justify left bottom)
				(hide yes)
			)
		)
		(pin "1"
		)
		(pin "2"
		)
		(instances
			(project "thunderbolt-to-10gbe-adapter"
				(path ""
					(reference "C33")
					(unit 1)
				)
			)
		)
	)
	(symbol
		(lib_id "antmicroResistors0402:R_1M_0402")
		(at 102.87 102.87 90)
		(unit 1)
		(exclude_from_sim no)
		(in_bom yes)
		(on_board yes)
		(dnp no)
		(fields_autoplaced yes)
		(property "Reference" "R54"
			(at 100.965 99.06 90)
			(effects
				(font
					(size 1.27 1.27)
					(thickness 0.15)
				)
				(justify left)
			)
		)
		(property "Value" "R_1M_0402"
			(at 115.57 82.55 0)
			(effects
				(font
					(size 1.27 1.27)
					(thickness 0.15)
				)
				(justify left bottom)
				(hide yes)
			)
		)
		(property "Footprint" "antmicro-footprints:R_0402_1005Metric"
			(at 118.11 82.55 0)
			(effects
				(font
					(size 1.27 1.27)
					(thickness 0.15)
				)
				(justify left bottom)
				(hide yes)
			)
		)
		(property "Datasheet" "https://www.bourns.com/docs/product-datasheets/cr.pdf"
			(at 120.65 82.55 0)
			(effects
				(font
					(size 1.27 1.27)
					(thickness 0.15)
				)
				(justify left bottom)
				(hide yes)
			)
		)
		(property "Description" "SMD Chip Resistor, 1 Mohm, ± 1%, 62.5 mW, 0402 [1005 Metric], Thick Film, General Purpose"
			(at 102.87 102.87 0)
			(effects
				(font
					(size 1.27 1.27)
				)
				(hide yes)
			)
		)
		(property "MPN" "CR0402-FX-1004GLF"
			(at 123.19 82.55 0)
			(effects
				(font
					(size 1.27 1.27)
					(thickness 0.15)
				)
				(justify left bottom)
				(hide yes)
			)
		)
		(property "Manufacturer" "Bourns"
			(at 125.73 82.55 0)
			(effects
				(font
					(size 1.27 1.27)
					(thickness 0.15)
				)
				(justify left bottom)
				(hide yes)
			)
		)
		(property "License" "Apache-2.0"
			(at 128.27 82.55 0)
			(effects
				(font
					(size 1.27 1.27)
					(thickness 0.15)
				)
				(justify left bottom)
				(hide yes)
			)
		)
		(property "Val" "1M"
			(at 100.965 101.6 90)
			(effects
				(font
					(size 1.27 1.27)
					(thickness 0.15)
				)
				(justify left)
			)
		)
		(property "Tolerance" "1%"
			(at 113.03 82.55 0)
			(effects
				(font
					(size 1.27 1.27)
				)
				(justify left bottom)
				(hide yes)
			)
		)
		(property "Author" "Antmicro"
			(at 130.81 82.55 0)
			(effects
				(font
					(size 1.27 1.27)
					(thickness 0.15)
				)
				(justify left bottom)
				(hide yes)
			)
		)
		(pin "1"
		)
		(pin "2"
		)
		(instances
			(project "thunderbolt-to-10gbe-adapter"
				(path ""
					(reference "R54")
					(unit 1)
				)
			)
		)
	)
	(symbol
		(lib_id "antmicroResistors0402:R_100R_0402")
		(at 257.81 184.15 0)
		(unit 1)
		(exclude_from_sim no)
		(in_bom yes)
		(on_board yes)
		(dnp no)
		(property "Reference" "R68"
			(at 256.54 182.88 0)
			(effects
				(font
					(size 1.27 1.27)
					(thickness 0.15)
				)
			)
		)
		(property "Value" "R_100R_0402"
			(at 278.13 196.85 0)
			(effects
				(font
					(size 1.27 1.27)
					(thickness 0.15)
				)
				(justify left bottom)
				(hide yes)
			)
		)
		(property "Footprint" "antmicro-footprints:R_0402_1005Metric"
			(at 278.13 199.39 0)
			(effects
				(font
					(size 1.27 1.27)
					(thickness 0.15)
				)
				(justify left bottom)
				(hide yes)
			)
		)
		(property "Datasheet" "https://www.bourns.com/docs/product-datasheets/cr.pdf"
			(at 278.13 201.93 0)
			(effects
				(font
					(size 1.27 1.27)
					(thickness 0.15)
				)
				(justify left bottom)
				(hide yes)
			)
		)
		(property "Description" "SMD Chip Resistor, 100 ohm, ± 1%, 62.5 mW, 0402 [1005 Metric], Thick Film, General Purpose"
			(at 257.81 184.15 0)
			(effects
				(font
					(size 1.27 1.27)
				)
				(hide yes)
			)
		)
		(property "MPN" "CR0402-FX-1000GLF"
			(at 278.13 204.47 0)
			(effects
				(font
					(size 1.27 1.27)
					(thickness 0.15)
				)
				(justify left bottom)
				(hide yes)
			)
		)
		(property "Manufacturer" "Bourns"
			(at 278.13 207.01 0)
			(effects
				(font
					(size 1.27 1.27)
					(thickness 0.15)
				)
				(justify left bottom)
				(hide yes)
			)
		)
		(property "License" "Apache-2.0"
			(at 278.13 209.55 0)
			(effects
				(font
					(size 1.27 1.27)
					(thickness 0.15)
				)
				(justify left bottom)
				(hide yes)
			)
		)
		(property "Val" "100R"
			(at 264.795 182.88 0)
			(effects
				(font
					(size 1.27 1.27)
					(thickness 0.15)
				)
			)
		)
		(property "Tolerance" "1%"
			(at 278.13 194.31 0)
			(effects
				(font
					(size 1.27 1.27)
				)
				(justify left bottom)
				(hide yes)
			)
		)
		(property "Author" "Antmicro"
			(at 278.13 212.09 0)
			(effects
				(font
					(size 1.27 1.27)
					(thickness 0.15)
				)
				(justify left bottom)
				(hide yes)
			)
		)
		(pin "1"
		)
		(pin "2"
		)
		(instances
			(project "thunderbolt-to-10gbe-adapter"
				(path ""
					(reference "R68")
					(unit 1)
				)
			)
		)
	)
	(symbol
		(lib_id "antmicroCapacitors0402:C_220n_0402")
		(at 100.33 68.58 0)
		(unit 1)
		(exclude_from_sim no)
		(in_bom yes)
		(on_board yes)
		(dnp no)
		(property "Reference" "C34"
			(at 99.695 67.31 0)
			(effects
				(font
					(size 1.27 1.27)
					(thickness 0.15)
				)
			)
		)
		(property "Value" "C_220n_0402"
			(at 120.65 78.74 0)
			(effects
				(font
					(size 1.27 1.27)
					(thickness 0.15)
				)
				(justify left bottom)
				(hide yes)
			)
		)
		(property "Footprint" "antmicro-footprints:C_0402_1005Metric"
			(at 120.65 81.28 0)
			(effects
				(font
					(size 1.27 1.27)
					(thickness 0.15)
				)
				(justify left bottom)
				(hide yes)
			)
		)
		(property "Datasheet" "https://www.yageo.com/en/Chart/Download/pdf/CC0402KRX5R6BB224"
			(at 120.65 83.82 0)
			(effects
				(font
					(size 1.27 1.27)
					(thickness 0.15)
				)
				(justify left bottom)
				(hide yes)
			)
		)
		(property "Description" "SMD Multilayer Ceramic Capacitor, 0.22 µF, 10 V, 0402 [1005 Metric], ± 10%, X5R, CC Series"
			(at 100.33 68.58 0)
			(effects
				(font
					(size 1.27 1.27)
				)
				(hide yes)
			)
		)
		(property "MPN" "CC0402KRX5R6BB224"
			(at 120.65 86.36 0)
			(effects
				(font
					(size 1.27 1.27)
					(thickness 0.15)
				)
				(justify left bottom)
				(hide yes)
			)
		)
		(property "Manufacturer" "YAGEO"
			(at 120.65 88.9 0)
			(effects
				(font
					(size 1.27 1.27)
					(thickness 0.15)
				)
				(justify left bottom)
				(hide yes)
			)
		)
		(property "License" "Apache-2.0"
			(at 120.65 91.44 0)
			(effects
				(font
					(size 1.27 1.27)
					(thickness 0.15)
				)
				(justify left bottom)
				(hide yes)
			)
		)
		(property "Val" "220n"
			(at 99.695 69.85 0)
			(effects
				(font
					(size 1.27 1.27)
					(thickness 0.15)
				)
			)
		)
		(property "Voltage" ""
			(at 120.65 96.52 0)
			(effects
				(font
					(size 1.27 1.27)
				)
				(justify left bottom)
				(hide yes)
			)
		)
		(property "Dielectric" ""
			(at 120.65 99.06 0)
			(effects
				(font
					(size 1.27 1.27)
				)
				(justify left bottom)
				(hide yes)
			)
		)
		(property "Author" "Antmicro"
			(at 120.65 93.98 0)
			(effects
				(font
					(size 1.27 1.27)
					(thickness 0.15)
				)
				(justify left bottom)
				(hide yes)
			)
		)
		(pin "1"
		)
		(pin "2"
		)
		(instances
			(project "thunderbolt-to-10gbe-adapter"
				(path ""
					(reference "C34")
					(unit 1)
				)
			)
		)
	)
	(symbol
		(lib_id "antmicroCapacitors0402:C_220n_0402")
		(at 341.63 71.12 0)
		(unit 1)
		(exclude_from_sim no)
		(in_bom yes)
		(on_board yes)
		(dnp no)
		(property "Reference" "C51"
			(at 340.614 72.39 0)
			(effects
				(font
					(size 1.27 1.27)
					(thickness 0.15)
				)
			)
		)
		(property "Value" "C_220n_0402"
			(at 361.95 81.28 0)
			(effects
				(font
					(size 1.27 1.27)
					(thickness 0.15)
				)
				(justify left bottom)
				(hide yes)
			)
		)
		(property "Footprint" "antmicro-footprints:C_0402_1005Metric"
			(at 361.95 83.82 0)
			(effects
				(font
					(size 1.27 1.27)
					(thickness 0.15)
				)
				(justify left bottom)
				(hide yes)
			)
		)
		(property "Datasheet" "https://www.yageo.com/en/Chart/Download/pdf/CC0402KRX5R6BB224"
			(at 361.95 86.36 0)
			(effects
				(font
					(size 1.27 1.27)
					(thickness 0.15)
				)
				(justify left bottom)
				(hide yes)
			)
		)
		(property "Description" "SMD Multilayer Ceramic Capacitor, 0.22 µF, 10 V, 0402 [1005 Metric], ± 10%, X5R, CC Series"
			(at 341.63 71.12 0)
			(effects
				(font
					(size 1.27 1.27)
				)
				(hide yes)
			)
		)
		(property "MPN" "CC0402KRX5R6BB224"
			(at 361.95 88.9 0)
			(effects
				(font
					(size 1.27 1.27)
					(thickness 0.15)
				)
				(justify left bottom)
				(hide yes)
			)
		)
		(property "Manufacturer" "YAGEO"
			(at 361.95 91.44 0)
			(effects
				(font
					(size 1.27 1.27)
					(thickness 0.15)
				)
				(justify left bottom)
				(hide yes)
			)
		)
		(property "License" "Apache-2.0"
			(at 361.95 93.98 0)
			(effects
				(font
					(size 1.27 1.27)
					(thickness 0.15)
				)
				(justify left bottom)
				(hide yes)
			)
		)
		(property "Val" "220n"
			(at 347.218 72.39 0)
			(effects
				(font
					(size 1.27 1.27)
					(thickness 0.15)
				)
			)
		)
		(property "Voltage" ""
			(at 361.95 99.06 0)
			(effects
				(font
					(size 1.27 1.27)
				)
				(justify left bottom)
				(hide yes)
			)
		)
		(property "Dielectric" ""
			(at 361.95 101.6 0)
			(effects
				(font
					(size 1.27 1.27)
				)
				(justify left bottom)
				(hide yes)
			)
		)
		(property "Author" "Antmicro"
			(at 361.95 96.52 0)
			(effects
				(font
					(size 1.27 1.27)
					(thickness 0.15)
				)
				(justify left bottom)
				(hide yes)
			)
		)
		(pin "1"
		)
		(pin "2"
		)
		(instances
			(project "thunderbolt-to-10gbe-adapter"
				(path ""
					(reference "C51")
					(unit 1)
				)
			)
		)
	)
	(symbol
		(lib_id "antmicroInterfaceControllers:JHL6340SLLSQ")
		(at 198.12 184.15 0)
		(unit 4)
		(exclude_from_sim no)
		(in_bom yes)
		(on_board yes)
		(dnp no)
		(fields_autoplaced yes)
		(property "Reference" "U4"
			(at 226.06 175.895 0)
			(effects
				(font
					(size 1.27 1.27)
					(thickness 0.15)
				)
			)
		)
		(property "Value" "JHL6340SLLSQ"
			(at 269.24 186.69 0)
			(effects
				(font
					(size 1.27 1.27)
					(thickness 0.15)
				)
				(justify left bottom)
				(hide yes)
			)
		)
		(property "Footprint" "antmicro-footprints:JHL6340SLLSQ"
			(at 269.24 189.23 0)
			(effects
				(font
					(size 1.27 1.27)
					(thickness 0.15)
				)
				(justify left bottom)
				(hide yes)
			)
		)
		(property "Datasheet" "https://www.thunderbolttechnology.net/sites/default/files/18-241_ThunderboltController_Brief_HI.pdf"
			(at 269.24 191.77 0)
			(effects
				(font
					(size 1.27 1.27)
					(thickness 0.15)
				)
				(justify left bottom)
				(hide yes)
			)
		)
		(property "Description" "Thunderbolt™ 3 Controller, I/O"
			(at 198.12 184.15 0)
			(effects
				(font
					(size 1.27 1.27)
				)
				(hide yes)
			)
		)
		(property "Manufacturer" "Intel"
			(at 269.24 194.31 0)
			(effects
				(font
					(size 1.27 1.27)
					(thickness 0.15)
				)
				(justify left bottom)
				(hide yes)
			)
		)
		(property "MPN" "JHL6340SLLSQ"
			(at 226.06 178.435 0)
			(effects
				(font
					(size 1.27 1.27)
					(thickness 0.15)
				)
			)
		)
		(property "Author" "Antmicro"
			(at 269.24 199.39 0)
			(effects
				(font
					(size 1.27 1.27)
					(thickness 0.15)
				)
				(justify left bottom)
				(hide yes)
			)
		)
		(property "License" "Apache-2.0"
			(at 269.24 201.93 0)
			(effects
				(font
					(size 1.27 1.27)
					(thickness 0.15)
				)
				(justify left bottom)
				(hide yes)
			)
		)
		(pin "V5"
		)
		(pin "Y9"
		)
		(pin "AC5"
		)
		(pin "F12"
		)
		(pin "L13"
		)
		(pin "A13"
		)
		(pin "T23"
		)
		(pin "AA2"
		)
		(pin "L22"
		)
		(pin "R16"
		)
		(pin "N13"
		)
		(pin "D9"
		)
		(pin "T2"
		)
		(pin "R12"
		)
		(pin "U1"
		)
		(pin "R23"
		)
		(pin "J23"
		)
		(pin "T22"
		)
		(pin "L23"
		)
		(pin "B3"
		)
		(pin "V4"
		)
		(pin "N8"
		)
		(pin "AB11"
		)
		(pin "AB4"
		)
		(pin "M6"
		)
		(pin "K22"
		)
		(pin "R5"
		)
		(pin "L15"
		)
		(pin "F13"
		)
		(pin "L12"
		)
		(pin "H20"
		)
		(pin "V15"
		)
		(pin "V22"
		)
		(pin "V19"
		)
		(pin "P23"
		)
		(pin "M18"
		)
		(pin "A4"
		)
		(pin "A9"
		)
		(pin "M23"
		)
		(pin "Y8"
		)
		(pin "Y4"
		)
		(pin "N5"
		)
		(pin "T5"
		)
		(pin "W1"
		)
		(pin "Y11"
		)
		(pin "Y5"
		)
		(pin "B22"
		)
		(pin "B6"
		)
		(pin "V8"
		)
		(pin "V1"
		)
		(pin "A17"
		)
		(pin "Y2"
		)
		(pin "W2"
		)
		(pin "R22"
		)
		(pin "N6"
		)
		(pin "F16"
		)
		(pin "AB13"
		)
		(pin "H4"
		)
		(pin "F22"
		)
		(pin "R4"
		)
		(pin "F23"
		)
		(pin "W11"
		)
		(pin "D13"
		)
		(pin "AC10"
		)
		(pin "M9"
		)
		(pin "V2"
		)
		(pin "L19"
		)
		(pin "T18"
		)
		(pin "L20"
		)
		(pin "H8"
		)
		(pin "AB7"
		)
		(pin "Y23"
		)
		(pin "K1"
		)
		(pin "AC7"
		)
		(pin "H18"
		)
		(pin "C1"
		)
		(pin "N1"
		)
		(pin "AB5"
		)
		(pin "J5"
		)
		(pin "R15"
		)
		(pin "M13"
		)
		(pin "D1"
		)
		(pin "E20"
		)
		(pin "AC11"
		)
		(pin "A5"
		)
		(pin "AB15"
		)
		(pin "L8"
		)
		(pin "D6"
		)
		(pin "D19"
		)
		(pin "V6"
		)
		(pin "N19"
		)
		(pin "T11"
		)
		(pin "W8"
		)
		(pin "C22"
		)
		(pin "H19"
		)
		(pin "L11"
		)
		(pin "AC13"
		)
		(pin "D2"
		)
		(pin "K23"
		)
		(pin "L2"
		)
		(pin "A7"
		)
		(pin "H16"
		)
		(pin "Y16"
		)
		(pin "V12"
		)
		(pin "AB9"
		)
		(pin "M20"
		)
		(pin "N20"
		)
		(pin "R19"
		)
		(pin "U22"
		)
		(pin "AB21"
		)
		(pin "E4"
		)
		(pin "R6"
		)
		(pin "R20"
		)
		(pin "AC1"
		)
		(pin "G2"
		)
		(pin "M8"
		)
		(pin "M16"
		)
		(pin "V20"
		)
		(pin "F18"
		)
		(pin "AB3"
		)
		(pin "AA1"
		)
		(pin "D22"
		)
		(pin "V11"
		)
		(pin "T1"
		)
		(pin "V18"
		)
		(pin "B9"
		)
		(pin "J9"
		)
		(pin "M5"
		)
		(pin "H15"
		)
		(pin "M12"
		)
		(pin "M15"
		)
		(pin "AC9"
		)
		(pin "W23"
		)
		(pin "V9"
		)
		(pin "B8"
		)
		(pin "N16"
		)
		(pin "B14"
		)
		(pin "AC23"
		)
		(pin "W18"
		)
		(pin "M1"
		)
		(pin "N15"
		)
		(pin "AB17"
		)
		(pin "U23"
		)
		(pin "Y22"
		)
		(pin "L9"
		)
		(pin "T13"
		)
		(pin "F11"
		)
		(pin "N4"
		)
		(pin "F19"
		)
		(pin "W6"
		)
		(pin "F15"
		)
		(pin "B7"
		)
		(pin "Y1"
		)
		(pin "A6"
		)
		(pin "B2"
		)
		(pin "B4"
		)
		(pin "R13"
		)
		(pin "K2"
		)
		(pin "N18"
		)
		(pin "B13"
		)
		(pin "T19"
		)
		(pin "W22"
		)
		(pin "H23"
		)
		(pin "T4"
		)
		(pin "L18"
		)
		(pin "E19"
		)
		(pin "H2"
		)
		(pin "L1"
		)
		(pin "F20"
		)
		(pin "B23"
		)
		(pin "R8"
		)
		(pin "M22"
		)
		(pin "F2"
		)
		(pin "E18"
		)
		(pin "R2"
		)
		(pin "W4"
		)
		(pin "B5"
		)
		(pin "W19"
		)
		(pin "N22"
		)
		(pin "D5"
		)
		(pin "W20"
		)
		(pin "W12"
		)
		(pin "B11"
		)
		(pin "R11"
		)
		(pin "E2"
		)
		(pin "D18"
		)
		(pin "T8"
		)
		(pin "L5"
		)
		(pin "M4"
		)
		(pin "T20"
		)
		(pin "A3"
		)
		(pin "AC3"
		)
		(pin "A19"
		)
		(pin "L16"
		)
		(pin "F4"
		)
		(pin "T12"
		)
		(pin "Y18"
		)
		(pin "T16"
		)
		(pin "AB19"
		)
		(pin "B12"
		)
		(pin "E23"
		)
		(pin "E1"
		)
		(pin "T6"
		)
		(pin "Y19"
		)
		(pin "T15"
		)
		(pin "P22"
		)
		(pin "AB16"
		)
		(pin "AC4"
		)
		(pin "D15"
		)
		(pin "G1"
		)
		(pin "A8"
		)
		(pin "Y12"
		)
		(pin "J4"
		)
		(pin "J1"
		)
		(pin "E22"
		)
		(pin "D20"
		)
		(pin "M2"
		)
		(pin "V23"
		)
		(pin "AB10"
		)
		(pin "AB2"
		)
		(pin "AC15"
		)
		(pin "D23"
		)
		(pin "A23"
		)
		(pin "C23"
		)
		(pin "J2"
		)
		(pin "A21"
		)
		(pin "F1"
		)
		(pin "H5"
		)
		(pin "N11"
		)
		(pin "B20"
		)
		(pin "H22"
		)
		(pin "AA23"
		)
		(pin "E13"
		)
		(pin "J12"
		)
		(pin "W9"
		)
		(pin "H9"
		)
		(pin "B19"
		)
		(pin "AB8"
		)
		(pin "AB22"
		)
		(pin "AB6"
		)
		(pin "AB20"
		)
		(pin "AC2"
		)
		(pin "E9"
		)
		(pin "J11"
		)
		(pin "L4"
		)
		(pin "J8"
		)
		(pin "AC22"
		)
		(pin "J13"
		)
		(pin "N12"
		)
		(pin "J15"
		)
		(pin "B18"
		)
		(pin "Y15"
		)
		(pin "U2"
		)
		(pin "AC12"
		)
		(pin "D16"
		)
		(pin "AB14"
		)
		(pin "AC6"
		)
		(pin "A14"
		)
		(pin "V13"
		)
		(pin "G22"
		)
		(pin "Y13"
		)
		(pin "B16"
		)
		(pin "AB18"
		)
		(pin "B17"
		)
		(pin "A20"
		)
		(pin "AB12"
		)
		(pin "R1"
		)
		(pin "AC20"
		)
		(pin "H12"
		)
		(pin "A2"
		)
		(pin "F5"
		)
		(pin "E6"
		)
		(pin "A10"
		)
		(pin "A12"
		)
		(pin "H11"
		)
		(pin "F9"
		)
		(pin "A1"
		)
		(pin "AB1"
		)
		(pin "E8"
		)
		(pin "A11"
		)
		(pin "L6"
		)
		(pin "B21"
		)
		(pin "AB23"
		)
		(pin "W13"
		)
		(pin "P2"
		)
		(pin "W16"
		)
		(pin "AC16"
		)
		(pin "H6"
		)
		(pin "Y6"
		)
		(pin "A15"
		)
		(pin "J6"
		)
		(pin "V16"
		)
		(pin "N9"
		)
		(pin "AC21"
		)
		(pin "J19"
		)
		(pin "J20"
		)
		(pin "AC17"
		)
		(pin "AC19"
		)
		(pin "M11"
		)
		(pin "D4"
		)
		(pin "P1"
		)
		(pin "W5"
		)
		(pin "R18"
		)
		(pin "E16"
		)
		(pin "N23"
		)
		(pin "A22"
		)
		(pin "R9"
		)
		(pin "D8"
		)
		(pin "E15"
		)
		(pin "M19"
		)
		(pin "Y20"
		)
		(pin "T9"
		)
		(pin "H13"
		)
		(pin "W15"
		)
		(pin "B10"
		)
		(pin "AC14"
		)
		(pin "AC18"
		)
		(pin "C2"
		)
		(pin "E5"
		)
		(pin "J22"
		)
		(pin "J18"
		)
		(pin "J16"
		)
		(pin "AC8"
		)
		(pin "B1"
		)
		(pin "N2"
		)
		(pin "E11"
		)
		(pin "A18"
		)
		(pin "H1"
		)
		(pin "G23"
		)
		(pin "A16"
		)
		(pin "D11"
		)
		(pin "B15"
		)
		(pin "F8"
		)
		(pin "E12"
		)
		(pin "AA22"
		)
		(pin "D12"
		)
		(pin "F6"
		)
		(instances
			(project "thunderbolt-to-10gbe-adapter"
				(path ""
					(reference "U4")
					(unit 4)
				)
			)
		)
	)
	(symbol
		(lib_id "antmicroResistors0402:R_2k2_0402")
		(at 33.02 208.28 0)
		(unit 1)
		(exclude_from_sim no)
		(in_bom yes)
		(on_board yes)
		(dnp no)
		(property "Reference" "R35"
			(at 35.56 206.375 0)
			(effects
				(font
					(size 1.27 1.27)
					(thickness 0.15)
				)
			)
		)
		(property "Value" "R_2k2_0402"
			(at 53.34 220.98 0)
			(effects
				(font
					(size 1.27 1.27)
					(thickness 0.15)
				)
				(justify left bottom)
				(hide yes)
			)
		)
		(property "Footprint" "antmicro-footprints:R_0402_1005Metric"
			(at 53.34 223.52 0)
			(effects
				(font
					(size 1.27 1.27)
					(thickness 0.15)
				)
				(justify left bottom)
				(hide yes)
			)
		)
		(property "Datasheet" "https://www.bourns.com/docs/product-datasheets/cr.pdf"
			(at 53.34 226.06 0)
			(effects
				(font
					(size 1.27 1.27)
					(thickness 0.15)
				)
				(justify left bottom)
				(hide yes)
			)
		)
		(property "Description" "SMD Chip Resistor, 2.2 kohm, ± 1%, 62.5 mW, 0402 [1005 Metric], Thick Film, General Purpose"
			(at 33.02 208.28 0)
			(effects
				(font
					(size 1.27 1.27)
				)
				(hide yes)
			)
		)
		(property "MPN" "CR0402-FX-2201GLF"
			(at 53.34 228.6 0)
			(effects
				(font
					(size 1.27 1.27)
					(thickness 0.15)
				)
				(justify left bottom)
				(hide yes)
			)
		)
		(property "Manufacturer" "Bourns"
			(at 53.34 231.14 0)
			(effects
				(font
					(size 1.27 1.27)
					(thickness 0.15)
				)
				(justify left bottom)
				(hide yes)
			)
		)
		(property "License" "Apache-2.0"
			(at 53.34 233.68 0)
			(effects
				(font
					(size 1.27 1.27)
					(thickness 0.15)
				)
				(justify left bottom)
				(hide yes)
			)
		)
		(property "Val" "2k2"
			(at 39.37 207.01 0)
			(effects
				(font
					(size 1.27 1.27)
					(thickness 0.15)
				)
			)
		)
		(property "Tolerance" "1%"
			(at 53.34 218.44 0)
			(effects
				(font
					(size 1.27 1.27)
				)
				(justify left bottom)
				(hide yes)
			)
		)
		(property "Author" "Antmicro"
			(at 53.34 236.22 0)
			(effects
				(font
					(size 1.27 1.27)
					(thickness 0.15)
				)
				(justify left bottom)
				(hide yes)
			)
		)
		(pin "1"
		)
		(pin "2"
		)
		(instances
			(project "thunderbolt-to-10gbe-adapter"
				(path ""
					(reference "R35")
					(unit 1)
				)
			)
		)
	)
	(symbol
		(lib_id "antmicroResistors0402:R_2k2_0402")
		(at 33.02 264.16 0)
		(unit 1)
		(exclude_from_sim no)
		(in_bom yes)
		(on_board yes)
		(dnp no)
		(property "Reference" "R39"
			(at 35.56 266.065 0)
			(effects
				(font
					(size 1.27 1.27)
					(thickness 0.15)
				)
			)
		)
		(property "Value" "R_2k2_0402"
			(at 53.34 276.86 0)
			(effects
				(font
					(size 1.27 1.27)
					(thickness 0.15)
				)
				(justify left bottom)
				(hide yes)
			)
		)
		(property "Footprint" "antmicro-footprints:R_0402_1005Metric"
			(at 53.34 279.4 0)
			(effects
				(font
					(size 1.27 1.27)
					(thickness 0.15)
				)
				(justify left bottom)
				(hide yes)
			)
		)
		(property "Datasheet" "https://www.bourns.com/docs/product-datasheets/cr.pdf"
			(at 53.34 281.94 0)
			(effects
				(font
					(size 1.27 1.27)
					(thickness 0.15)
				)
				(justify left bottom)
				(hide yes)
			)
		)
		(property "Description" "SMD Chip Resistor, 2.2 kohm, ± 1%, 62.5 mW, 0402 [1005 Metric], Thick Film, General Purpose"
			(at 33.02 264.16 0)
			(effects
				(font
					(size 1.27 1.27)
				)
				(hide yes)
			)
		)
		(property "MPN" "CR0402-FX-2201GLF"
			(at 53.34 284.48 0)
			(effects
				(font
					(size 1.27 1.27)
					(thickness 0.15)
				)
				(justify left bottom)
				(hide yes)
			)
		)
		(property "Manufacturer" "Bourns"
			(at 53.34 287.02 0)
			(effects
				(font
					(size 1.27 1.27)
					(thickness 0.15)
				)
				(justify left bottom)
				(hide yes)
			)
		)
		(property "License" "Apache-2.0"
			(at 53.34 289.56 0)
			(effects
				(font
					(size 1.27 1.27)
					(thickness 0.15)
				)
				(justify left bottom)
				(hide yes)
			)
		)
		(property "Val" "2k2"
			(at 39.37 265.43 0)
			(effects
				(font
					(size 1.27 1.27)
					(thickness 0.15)
				)
			)
		)
		(property "Tolerance" "1%"
			(at 53.34 274.32 0)
			(effects
				(font
					(size 1.27 1.27)
				)
				(justify left bottom)
				(hide yes)
			)
		)
		(property "Author" "Antmicro"
			(at 53.34 292.1 0)
			(effects
				(font
					(size 1.27 1.27)
					(thickness 0.15)
				)
				(justify left bottom)
				(hide yes)
			)
		)
		(pin "1"
		)
		(pin "2"
		)
		(instances
			(project "thunderbolt-to-10gbe-adapter"
				(path ""
					(reference "R39")
					(unit 1)
				)
			)
		)
	)
	(symbol
		(lib_id "antmicroCapacitors0402:C_10p_0402")
		(at 302.26 185.42 0)
		(unit 1)
		(exclude_from_sim no)
		(in_bom yes)
		(on_board yes)
		(dnp no)
		(property "Reference" "C42"
			(at 301.244 183.896 0)
			(effects
				(font
					(size 1.27 1.27)
					(thickness 0.15)
				)
			)
		)
		(property "Value" "C_10p_0402"
			(at 322.58 195.58 0)
			(effects
				(font
					(size 1.27 1.27)
					(thickness 0.15)
				)
				(justify left bottom)
				(hide yes)
			)
		)
		(property "Footprint" "antmicro-footprints:C_0402_1005Metric"
			(at 322.58 198.12 0)
			(effects
				(font
					(size 1.27 1.27)
					(thickness 0.15)
				)
				(justify left bottom)
				(hide yes)
			)
		)
		(property "Datasheet" "https://www.murata.com/products/productdetail?partno=GCM1555C1H100GA16%23"
			(at 322.58 200.66 0)
			(effects
				(font
					(size 1.27 1.27)
					(thickness 0.15)
				)
				(justify left bottom)
				(hide yes)
			)
		)
		(property "Description" "SMD Multilayer Ceramic Capacitor, 10 pF, 50 V, 0402 [1005 Metric], ± 2%, C0G / NP0, GCM"
			(at 302.26 185.42 0)
			(effects
				(font
					(size 1.27 1.27)
				)
				(hide yes)
			)
		)
		(property "MPN" "GCM1555C1H100GA16D"
			(at 322.58 203.2 0)
			(effects
				(font
					(size 1.27 1.27)
					(thickness 0.15)
				)
				(justify left bottom)
				(hide yes)
			)
		)
		(property "Manufacturer" "Murata"
			(at 322.58 205.74 0)
			(effects
				(font
					(size 1.27 1.27)
					(thickness 0.15)
				)
				(justify left bottom)
				(hide yes)
			)
		)
		(property "License" "Apache-2.0"
			(at 322.58 208.28 0)
			(effects
				(font
					(size 1.27 1.27)
					(thickness 0.15)
				)
				(justify left bottom)
				(hide yes)
			)
		)
		(property "Val" "10p"
			(at 307.594 184.15 0)
			(effects
				(font
					(size 1.27 1.27)
					(thickness 0.15)
				)
			)
		)
		(property "Voltage" "50V"
			(at 322.58 213.36 0)
			(effects
				(font
					(size 1.27 1.27)
				)
				(justify left bottom)
				(hide yes)
			)
		)
		(property "Dielectric" "C0G"
			(at 322.58 215.9 0)
			(effects
				(font
					(size 1.27 1.27)
				)
				(justify left bottom)
				(hide yes)
			)
		)
		(property "Author" "Antmicro"
			(at 322.58 210.82 0)
			(effects
				(font
					(size 1.27 1.27)
					(thickness 0.15)
				)
				(justify left bottom)
				(hide yes)
			)
		)
		(pin "1"
		)
		(pin "2"
		)
		(instances
			(project "thunderbolt-to-10gbe-adapter"
				(path ""
					(reference "C42")
					(unit 1)
				)
			)
		)
	)
	(symbol
		(lib_id "antmicroResonators:Resonator_25MHz_ABM8G")
		(at 299.72 194.31 90)
		(unit 1)
		(exclude_from_sim no)
		(in_bom yes)
		(on_board yes)
		(dnp no)
		(fields_autoplaced yes)
		(property "Reference" "Y2"
			(at 295.91 189.23 90)
			(effects
				(font
					(size 1.27 1.27)
					(thickness 0.15)
				)
				(justify left)
			)
		)
		(property "Value" "Resonator_25MHz_ABM8G"
			(at 312.42 179.07 0)
			(effects
				(font
					(size 1.27 1.27)
					(thickness 0.15)
				)
				(justify left bottom)
				(hide yes)
			)
		)
		(property "Footprint" "antmicro-footprints:Resonator_SMD_Abracon_ABM8G_3.2x2.5mm"
			(at 314.96 179.07 0)
			(effects
				(font
					(size 1.27 1.27)
					(thickness 0.15)
				)
				(justify left bottom)
				(hide yes)
			)
		)
		(property "Datasheet" "https://abracon.com/Resonators/ABM8G.pdf"
			(at 317.5 179.07 0)
			(effects
				(font
					(size 1.27 1.27)
					(thickness 0.15)
				)
				(justify left bottom)
				(hide yes)
			)
		)
		(property "Description" "Crystal, 25 MHz, SMD, 3.2mm x 2.5mm, 30 ppm, 18 pF, 20 ppm, ABM8G"
			(at 299.72 194.31 0)
			(effects
				(font
					(size 1.27 1.27)
				)
				(hide yes)
			)
		)
		(property "MPN" "ABM8G-25.000MHZ-18-D2Y-T3"
			(at 295.91 190.5 90)
			(effects
				(font
					(size 1.27 1.27)
					(thickness 0.15)
				)
				(justify left)
				(hide yes)
			)
		)
		(property "Manufacturer" "Abracon"
			(at 320.04 179.07 0)
			(effects
				(font
					(size 1.27 1.27)
					(thickness 0.15)
				)
				(justify left bottom)
				(hide yes)
			)
		)
		(property "License" "Apache-2.0"
			(at 325.12 179.07 0)
			(effects
				(font
					(size 1.27 1.27)
					(thickness 0.15)
				)
				(justify left bottom)
				(hide yes)
			)
		)
		(property "Author" "Antmicro"
			(at 322.58 179.07 0)
			(effects
				(font
					(size 1.27 1.27)
					(thickness 0.15)
				)
				(justify left bottom)
				(hide yes)
			)
		)
		(property "Val" "25 MHz"
			(at 295.91 191.77 90)
			(effects
				(font
					(size 1.27 1.27)
					(thickness 0.15)
				)
				(justify left)
			)
		)
		(pin "1"
		)
		(pin "2"
		)
		(pin "3"
		)
		(pin "4"
		)
		(instances
			(project "thunderbolt-to-10gbe-adapter"
				(path ""
					(reference "Y2")
					(unit 1)
				)
			)
		)
	)
	(symbol
		(lib_id "antmicroCapacitors0402:C_220n_0402")
		(at 341.63 55.88 0)
		(unit 1)
		(exclude_from_sim no)
		(in_bom yes)
		(on_board yes)
		(dnp no)
		(property "Reference" "C49"
			(at 340.868 57.15 0)
			(effects
				(font
					(size 1.27 1.27)
					(thickness 0.15)
				)
			)
		)
		(property "Value" "C_220n_0402"
			(at 361.95 66.04 0)
			(effects
				(font
					(size 1.27 1.27)
					(thickness 0.15)
				)
				(justify left bottom)
				(hide yes)
			)
		)
		(property "Footprint" "antmicro-footprints:C_0402_1005Metric"
			(at 361.95 68.58 0)
			(effects
				(font
					(size 1.27 1.27)
					(thickness 0.15)
				)
				(justify left bottom)
				(hide yes)
			)
		)
		(property "Datasheet" "https://www.yageo.com/en/Chart/Download/pdf/CC0402KRX5R6BB224"
			(at 361.95 71.12 0)
			(effects
				(font
					(size 1.27 1.27)
					(thickness 0.15)
				)
				(justify left bottom)
				(hide yes)
			)
		)
		(property "Description" "SMD Multilayer Ceramic Capacitor, 0.22 µF, 10 V, 0402 [1005 Metric], ± 10%, X5R, CC Series"
			(at 341.63 55.88 0)
			(effects
				(font
					(size 1.27 1.27)
				)
				(hide yes)
			)
		)
		(property "MPN" "CC0402KRX5R6BB224"
			(at 361.95 73.66 0)
			(effects
				(font
					(size 1.27 1.27)
					(thickness 0.15)
				)
				(justify left bottom)
				(hide yes)
			)
		)
		(property "Manufacturer" "YAGEO"
			(at 361.95 76.2 0)
			(effects
				(font
					(size 1.27 1.27)
					(thickness 0.15)
				)
				(justify left bottom)
				(hide yes)
			)
		)
		(property "License" "Apache-2.0"
			(at 361.95 78.74 0)
			(effects
				(font
					(size 1.27 1.27)
					(thickness 0.15)
				)
				(justify left bottom)
				(hide yes)
			)
		)
		(property "Val" "220n"
			(at 347.726 57.15 0)
			(effects
				(font
					(size 1.27 1.27)
					(thickness 0.15)
				)
			)
		)
		(property "Voltage" ""
			(at 361.95 83.82 0)
			(effects
				(font
					(size 1.27 1.27)
				)
				(justify left bottom)
				(hide yes)
			)
		)
		(property "Dielectric" ""
			(at 361.95 86.36 0)
			(effects
				(font
					(size 1.27 1.27)
				)
				(justify left bottom)
				(hide yes)
			)
		)
		(property "Author" "Antmicro"
			(at 361.95 81.28 0)
			(effects
				(font
					(size 1.27 1.27)
					(thickness 0.15)
				)
				(justify left bottom)
				(hide yes)
			)
		)
		(pin "1"
		)
		(pin "2"
		)
		(instances
			(project "thunderbolt-to-10gbe-adapter"
				(path ""
					(reference "C49")
					(unit 1)
				)
			)
		)
	)
	(symbol
		(lib_id "antmicroResistors0402:R_1M_0402")
		(at 185.42 93.98 0)
		(unit 1)
		(exclude_from_sim no)
		(in_bom yes)
		(on_board yes)
		(dnp no)
		(property "Reference" "R59"
			(at 184.15 92.71 0)
			(effects
				(font
					(size 1.27 1.27)
					(thickness 0.15)
				)
			)
		)
		(property "Value" "R_1M_0402"
			(at 205.74 106.68 0)
			(effects
				(font
					(size 1.27 1.27)
					(thickness 0.15)
				)
				(justify left bottom)
				(hide yes)
			)
		)
		(property "Footprint" "antmicro-footprints:R_0402_1005Metric"
			(at 205.74 109.22 0)
			(effects
				(font
					(size 1.27 1.27)
					(thickness 0.15)
				)
				(justify left bottom)
				(hide yes)
			)
		)
		(property "Datasheet" "https://www.bourns.com/docs/product-datasheets/cr.pdf"
			(at 205.74 111.76 0)
			(effects
				(font
					(size 1.27 1.27)
					(thickness 0.15)
				)
				(justify left bottom)
				(hide yes)
			)
		)
		(property "Description" "SMD Chip Resistor, 1 Mohm, ± 1%, 62.5 mW, 0402 [1005 Metric], Thick Film, General Purpose"
			(at 185.42 93.98 0)
			(effects
				(font
					(size 1.27 1.27)
				)
				(hide yes)
			)
		)
		(property "MPN" "CR0402-FX-1004GLF"
			(at 205.74 114.3 0)
			(effects
				(font
					(size 1.27 1.27)
					(thickness 0.15)
				)
				(justify left bottom)
				(hide yes)
			)
		)
		(property "Manufacturer" "Bourns"
			(at 205.74 116.84 0)
			(effects
				(font
					(size 1.27 1.27)
					(thickness 0.15)
				)
				(justify left bottom)
				(hide yes)
			)
		)
		(property "License" "Apache-2.0"
			(at 205.74 119.38 0)
			(effects
				(font
					(size 1.27 1.27)
					(thickness 0.15)
				)
				(justify left bottom)
				(hide yes)
			)
		)
		(property "Val" "1M"
			(at 191.77 92.71 0)
			(effects
				(font
					(size 1.27 1.27)
					(thickness 0.15)
				)
			)
		)
		(property "Tolerance" "1%"
			(at 205.74 104.14 0)
			(effects
				(font
					(size 1.27 1.27)
				)
				(justify left bottom)
				(hide yes)
			)
		)
		(property "Author" "Antmicro"
			(at 205.74 121.92 0)
			(effects
				(font
					(size 1.27 1.27)
					(thickness 0.15)
				)
				(justify left bottom)
				(hide yes)
			)
		)
		(pin "1"
		)
		(pin "2"
		)
		(instances
			(project "thunderbolt-to-10gbe-adapter"
				(path ""
					(reference "R59")
					(unit 1)
				)
			)
		)
	)
	(symbol
		(lib_id "antmicroCapacitors0402:C_10p_0402")
		(at 246.38 118.11 0)
		(unit 1)
		(exclude_from_sim no)
		(in_bom yes)
		(on_board yes)
		(dnp no)
		(fields_autoplaced yes)
		(property "Reference" "C39"
			(at 248.9263 111.76 0)
			(effects
				(font
					(size 1.27 1.27)
					(thickness 0.15)
				)
			)
		)
		(property "Value" "C_10p_0402"
			(at 266.7 128.27 0)
			(effects
				(font
					(size 1.27 1.27)
					(thickness 0.15)
				)
				(justify left bottom)
				(hide yes)
			)
		)
		(property "Footprint" "antmicro-footprints:C_0402_1005Metric"
			(at 266.7 130.81 0)
			(effects
				(font
					(size 1.27 1.27)
					(thickness 0.15)
				)
				(justify left bottom)
				(hide yes)
			)
		)
		(property "Datasheet" "https://www.murata.com/products/productdetail?partno=GCM1555C1H100GA16%23"
			(at 266.7 133.35 0)
			(effects
				(font
					(size 1.27 1.27)
					(thickness 0.15)
				)
				(justify left bottom)
				(hide yes)
			)
		)
		(property "Description" "SMD Multilayer Ceramic Capacitor, 10 pF, 50 V, 0402 [1005 Metric], ± 2%, C0G / NP0, GCM"
			(at 246.38 118.11 0)
			(effects
				(font
					(size 1.27 1.27)
				)
				(hide yes)
			)
		)
		(property "MPN" "GCM1555C1H100GA16D"
			(at 266.7 135.89 0)
			(effects
				(font
					(size 1.27 1.27)
					(thickness 0.15)
				)
				(justify left bottom)
				(hide yes)
			)
		)
		(property "Manufacturer" "Murata"
			(at 266.7 138.43 0)
			(effects
				(font
					(size 1.27 1.27)
					(thickness 0.15)
				)
				(justify left bottom)
				(hide yes)
			)
		)
		(property "License" "Apache-2.0"
			(at 266.7 140.97 0)
			(effects
				(font
					(size 1.27 1.27)
					(thickness 0.15)
				)
				(justify left bottom)
				(hide yes)
			)
		)
		(property "Val" "10p"
			(at 248.9263 114.3 0)
			(effects
				(font
					(size 1.27 1.27)
					(thickness 0.15)
				)
			)
		)
		(property "Voltage" "50V"
			(at 266.7 146.05 0)
			(effects
				(font
					(size 1.27 1.27)
				)
				(justify left bottom)
				(hide yes)
			)
		)
		(property "Dielectric" "C0G"
			(at 266.7 148.59 0)
			(effects
				(font
					(size 1.27 1.27)
				)
				(justify left bottom)
				(hide yes)
			)
		)
		(property "Author" "Antmicro"
			(at 266.7 143.51 0)
			(effects
				(font
					(size 1.27 1.27)
					(thickness 0.15)
				)
				(justify left bottom)
				(hide yes)
			)
		)
		(pin "1"
		)
		(pin "2"
		)
		(instances
			(project "thunderbolt-to-10gbe-adapter"
				(path ""
					(reference "C39")
					(unit 1)
				)
			)
		)
	)
	(symbol
		(lib_id "antmicropower:GND")
		(at 113.03 209.55 0)
		(unit 1)
		(exclude_from_sim no)
		(in_bom yes)
		(on_board yes)
		(dnp no)
		(property "Reference" "#PWR062"
			(at 113.03 215.9 0)
			(effects
				(font
					(size 1.27 1.27)
				)
				(hide yes)
			)
		)
		(property "Value" "GND"
			(at 113.03 213.36 0)
			(effects
				(font
					(size 1.27 1.27)
				)
			)
		)
		(property "Footprint" ""
			(at 113.03 209.55 0)
			(effects
				(font
					(size 1.27 1.27)
				)
				(hide yes)
			)
		)
		(property "Datasheet" ""
			(at 113.03 209.55 0)
			(effects
				(font
					(size 1.27 1.27)
				)
				(hide yes)
			)
		)
		(property "Description" ""
			(at 113.03 209.55 0)
			(effects
				(font
					(size 1.27 1.27)
				)
				(hide yes)
			)
		)
		(property "Author" "Antmicro"
			(at 121.92 217.17 0)
			(effects
				(font
					(size 1.27 1.27)
					(thickness 0.15)
				)
				(justify left bottom)
				(hide yes)
			)
		)
		(property "License" "Apache-2.0"
			(at 121.92 219.71 0)
			(effects
				(font
					(size 1.27 1.27)
					(thickness 0.15)
				)
				(justify left bottom)
				(hide yes)
			)
		)
		(pin "1"
		)
		(instances
			(project "thunderbolt-to-10gbe-adapter"
				(path ""
					(reference "#PWR062")
					(unit 1)
				)
			)
		)
	)
	(symbol
		(lib_id "antmicroResistors0402:R_10k_0402")
		(at 101.6 226.06 0)
		(unit 1)
		(exclude_from_sim no)
		(in_bom yes)
		(on_board yes)
		(dnp no)
		(property "Reference" "R44"
			(at 100.33 224.79 0)
			(effects
				(font
					(size 1.27 1.27)
					(thickness 0.15)
				)
			)
		)
		(property "Value" "R_10k_0402"
			(at 121.92 238.76 0)
			(effects
				(font
					(size 1.27 1.27)
					(thickness 0.15)
				)
				(justify left bottom)
				(hide yes)
			)
		)
		(property "Footprint" "antmicro-footprints:R_0402_1005Metric"
			(at 121.92 241.3 0)
			(effects
				(font
					(size 1.27 1.27)
					(thickness 0.15)
				)
				(justify left bottom)
				(hide yes)
			)
		)
		(property "Datasheet" "https://www.bourns.com/docs/product-datasheets/cr.pdf"
			(at 121.92 243.84 0)
			(effects
				(font
					(size 1.27 1.27)
					(thickness 0.15)
				)
				(justify left bottom)
				(hide yes)
			)
		)
		(property "Description" "SMD Chip Resistor, 10 kohm, ± 1%, 62.5 mW, 0402 [1005 Metric], Thick Film, General Purpose"
			(at 101.6 226.06 0)
			(effects
				(font
					(size 1.27 1.27)
				)
				(hide yes)
			)
		)
		(property "MPN" "CR0402-FX-1002GLF"
			(at 121.92 246.38 0)
			(effects
				(font
					(size 1.27 1.27)
					(thickness 0.15)
				)
				(justify left bottom)
				(hide yes)
			)
		)
		(property "Manufacturer" "Bourns"
			(at 121.92 248.92 0)
			(effects
				(font
					(size 1.27 1.27)
					(thickness 0.15)
				)
				(justify left bottom)
				(hide yes)
			)
		)
		(property "License" "Apache-2.0"
			(at 121.92 251.46 0)
			(effects
				(font
					(size 1.27 1.27)
					(thickness 0.15)
				)
				(justify left bottom)
				(hide yes)
			)
		)
		(property "Val" "10k"
			(at 107.95 224.79 0)
			(effects
				(font
					(size 1.27 1.27)
					(thickness 0.15)
				)
			)
		)
		(property "Tolerance" "1%"
			(at 121.92 236.22 0)
			(effects
				(font
					(size 1.27 1.27)
				)
				(justify left bottom)
				(hide yes)
			)
		)
		(property "Author" "Antmicro"
			(at 121.92 254 0)
			(effects
				(font
					(size 1.27 1.27)
					(thickness 0.15)
				)
				(justify left bottom)
				(hide yes)
			)
		)
		(pin "1"
		)
		(pin "2"
		)
		(instances
			(project "thunderbolt-to-10gbe-adapter"
				(path ""
					(reference "R44")
					(unit 1)
				)
			)
		)
	)
	(symbol
		(lib_id "antmicropower:GND")
		(at 116.84 102.87 0)
		(mirror y)
		(unit 1)
		(exclude_from_sim no)
		(in_bom yes)
		(on_board yes)
		(dnp no)
		(property "Reference" "#PWR065"
			(at 116.84 109.22 0)
			(effects
				(font
					(size 1.27 1.27)
				)
				(hide yes)
			)
		)
		(property "Value" "GND"
			(at 116.84 106.68 0)
			(effects
				(font
					(size 1.27 1.27)
				)
			)
		)
		(property "Footprint" ""
			(at 116.84 102.87 0)
			(effects
				(font
					(size 1.27 1.27)
				)
				(hide yes)
			)
		)
		(property "Datasheet" ""
			(at 116.84 102.87 0)
			(effects
				(font
					(size 1.27 1.27)
				)
				(hide yes)
			)
		)
		(property "Description" ""
			(at 116.84 102.87 0)
			(effects
				(font
					(size 1.27 1.27)
				)
				(hide yes)
			)
		)
		(property "Author" "Antmicro"
			(at 107.95 110.49 0)
			(effects
				(font
					(size 1.27 1.27)
					(thickness 0.15)
				)
				(justify left bottom)
				(hide yes)
			)
		)
		(property "License" "Apache-2.0"
			(at 107.95 113.03 0)
			(effects
				(font
					(size 1.27 1.27)
					(thickness 0.15)
				)
				(justify left bottom)
				(hide yes)
			)
		)
		(pin "1"
		)
		(instances
			(project "thunderbolt-to-10gbe-adapter"
				(path ""
					(reference "#PWR065")
					(unit 1)
				)
			)
		)
	)
	(symbol
		(lib_id "antmicroResistors0402:R_1M_0402")
		(at 185.42 91.44 0)
		(unit 1)
		(exclude_from_sim no)
		(in_bom yes)
		(on_board yes)
		(dnp no)
		(property "Reference" "R58"
			(at 184.15 90.17 0)
			(effects
				(font
					(size 1.27 1.27)
					(thickness 0.15)
				)
			)
		)
		(property "Value" "R_1M_0402"
			(at 205.74 104.14 0)
			(effects
				(font
					(size 1.27 1.27)
					(thickness 0.15)
				)
				(justify left bottom)
				(hide yes)
			)
		)
		(property "Footprint" "antmicro-footprints:R_0402_1005Metric"
			(at 205.74 106.68 0)
			(effects
				(font
					(size 1.27 1.27)
					(thickness 0.15)
				)
				(justify left bottom)
				(hide yes)
			)
		)
		(property "Datasheet" "https://www.bourns.com/docs/product-datasheets/cr.pdf"
			(at 205.74 109.22 0)
			(effects
				(font
					(size 1.27 1.27)
					(thickness 0.15)
				)
				(justify left bottom)
				(hide yes)
			)
		)
		(property "Description" "SMD Chip Resistor, 1 Mohm, ± 1%, 62.5 mW, 0402 [1005 Metric], Thick Film, General Purpose"
			(at 185.42 91.44 0)
			(effects
				(font
					(size 1.27 1.27)
				)
				(hide yes)
			)
		)
		(property "MPN" "CR0402-FX-1004GLF"
			(at 205.74 111.76 0)
			(effects
				(font
					(size 1.27 1.27)
					(thickness 0.15)
				)
				(justify left bottom)
				(hide yes)
			)
		)
		(property "Manufacturer" "Bourns"
			(at 205.74 114.3 0)
			(effects
				(font
					(size 1.27 1.27)
					(thickness 0.15)
				)
				(justify left bottom)
				(hide yes)
			)
		)
		(property "License" "Apache-2.0"
			(at 205.74 116.84 0)
			(effects
				(font
					(size 1.27 1.27)
					(thickness 0.15)
				)
				(justify left bottom)
				(hide yes)
			)
		)
		(property "Val" "1M"
			(at 191.77 90.17 0)
			(effects
				(font
					(size 1.27 1.27)
					(thickness 0.15)
				)
			)
		)
		(property "Tolerance" "1%"
			(at 205.74 101.6 0)
			(effects
				(font
					(size 1.27 1.27)
				)
				(justify left bottom)
				(hide yes)
			)
		)
		(property "Author" "Antmicro"
			(at 205.74 119.38 0)
			(effects
				(font
					(size 1.27 1.27)
					(thickness 0.15)
				)
				(justify left bottom)
				(hide yes)
			)
		)
		(pin "1"
		)
		(pin "2"
		)
		(instances
			(project "thunderbolt-to-10gbe-adapter"
				(path ""
					(reference "R58")
					(unit 1)
				)
			)
		)
	)
	(symbol
		(lib_id "antmicropower:GND")
		(at 102.87 105.41 0)
		(unit 1)
		(exclude_from_sim no)
		(in_bom yes)
		(on_board yes)
		(dnp no)
		(property "Reference" "#PWR060"
			(at 102.87 111.76 0)
			(effects
				(font
					(size 1.27 1.27)
				)
				(hide yes)
			)
		)
		(property "Value" "GND"
			(at 102.87 109.22 0)
			(effects
				(font
					(size 1.27 1.27)
				)
			)
		)
		(property "Footprint" ""
			(at 102.87 105.41 0)
			(effects
				(font
					(size 1.27 1.27)
				)
				(hide yes)
			)
		)
		(property "Datasheet" ""
			(at 102.87 105.41 0)
			(effects
				(font
					(size 1.27 1.27)
				)
				(hide yes)
			)
		)
		(property "Description" ""
			(at 102.87 105.41 0)
			(effects
				(font
					(size 1.27 1.27)
				)
				(hide yes)
			)
		)
		(property "Author" "Antmicro"
			(at 111.76 113.03 0)
			(effects
				(font
					(size 1.27 1.27)
					(thickness 0.15)
				)
				(justify left bottom)
				(hide yes)
			)
		)
		(property "License" "Apache-2.0"
			(at 111.76 115.57 0)
			(effects
				(font
					(size 1.27 1.27)
					(thickness 0.15)
				)
				(justify left bottom)
				(hide yes)
			)
		)
		(pin "1"
		)
		(instances
			(project "thunderbolt-to-10gbe-adapter"
				(path ""
					(reference "#PWR060")
					(unit 1)
				)
			)
		)
	)
	(symbol
		(lib_id "antmicroResistors0402:R_4k75_0.5%_0402")
		(at 195.58 205.74 90)
		(unit 1)
		(exclude_from_sim no)
		(in_bom yes)
		(on_board yes)
		(dnp no)
		(fields_autoplaced yes)
		(property "Reference" "R66"
			(at 193.675 201.93 90)
			(effects
				(font
					(size 1.27 1.27)
					(thickness 0.15)
				)
				(justify left)
			)
		)
		(property "Value" "R_4k75_0.5%_0402"
			(at 208.28 185.42 0)
			(effects
				(font
					(size 1.27 1.27)
					(thickness 0.15)
				)
				(justify left bottom)
				(hide yes)
			)
		)
		(property "Footprint" "antmicro-footprints:R_0402_1005Metric"
			(at 210.82 185.42 0)
			(effects
				(font
					(size 1.27 1.27)
					(thickness 0.15)
				)
				(justify left bottom)
				(hide yes)
			)
		)
		(property "Datasheet" "https://industrial.panasonic.com/cdbs/www-data/pdf/RDQ0000/ast-ind-151033.pdf"
			(at 213.36 185.42 0)
			(effects
				(font
					(size 1.27 1.27)
					(thickness 0.15)
				)
				(justify left bottom)
				(hide yes)
			)
		)
		(property "Description" "SMD Chip Resistor, 4.75 kohm, ± 0.5%, 100 mW, 0402 [1005 Metric], Thick Film, High Temperature"
			(at 195.58 205.74 0)
			(effects
				(font
					(size 1.27 1.27)
				)
				(hide yes)
			)
		)
		(property "MPN" "ERJ-H2RD4751X"
			(at 215.9 185.42 0)
			(effects
				(font
					(size 1.27 1.27)
					(thickness 0.15)
				)
				(justify left bottom)
				(hide yes)
			)
		)
		(property "Manufacturer" "Panasonic"
			(at 218.44 185.42 0)
			(effects
				(font
					(size 1.27 1.27)
					(thickness 0.15)
				)
				(justify left bottom)
				(hide yes)
			)
		)
		(property "License" "Apache-2.0"
			(at 220.98 185.42 0)
			(effects
				(font
					(size 1.27 1.27)
					(thickness 0.15)
				)
				(justify left bottom)
				(hide yes)
			)
		)
		(property "Val" "4k75"
			(at 193.675 204.47 90)
			(effects
				(font
					(size 1.27 1.27)
					(thickness 0.15)
				)
				(justify left)
			)
		)
		(property "Tolerance" "0.5%"
			(at 193.04 205.74 90)
			(effects
				(font
					(size 1.27 1.27)
				)
				(justify left)
				(hide yes)
			)
		)
		(property "Author" "Antmicro"
			(at 223.52 185.42 0)
			(effects
				(font
					(size 1.27 1.27)
					(thickness 0.15)
				)
				(justify left bottom)
				(hide yes)
			)
		)
		(pin "1"
		)
		(pin "2"
		)
		(instances
			(project "thunderbolt-to-10gbe-adapter"
				(path ""
					(reference "R66")
					(unit 1)
				)
			)
		)
	)
	(symbol
		(lib_id "antmicroCapacitors0402:C_220n_0402")
		(at 339.09 60.96 0)
		(unit 1)
		(exclude_from_sim no)
		(in_bom yes)
		(on_board yes)
		(dnp no)
		(property "Reference" "C46"
			(at 338.328 59.944 0)
			(effects
				(font
					(size 1.27 1.27)
					(thickness 0.15)
				)
			)
		)
		(property "Value" "C_220n_0402"
			(at 359.41 71.12 0)
			(effects
				(font
					(size 1.27 1.27)
					(thickness 0.15)
				)
				(justify left bottom)
				(hide yes)
			)
		)
		(property "Footprint" "antmicro-footprints:C_0402_1005Metric"
			(at 359.41 73.66 0)
			(effects
				(font
					(size 1.27 1.27)
					(thickness 0.15)
				)
				(justify left bottom)
				(hide yes)
			)
		)
		(property "Datasheet" "https://www.yageo.com/en/Chart/Download/pdf/CC0402KRX5R6BB224"
			(at 359.41 76.2 0)
			(effects
				(font
					(size 1.27 1.27)
					(thickness 0.15)
				)
				(justify left bottom)
				(hide yes)
			)
		)
		(property "Description" "SMD Multilayer Ceramic Capacitor, 0.22 µF, 10 V, 0402 [1005 Metric], ± 10%, X5R, CC Series"
			(at 339.09 60.96 0)
			(effects
				(font
					(size 1.27 1.27)
				)
				(hide yes)
			)
		)
		(property "MPN" "CC0402KRX5R6BB224"
			(at 359.41 78.74 0)
			(effects
				(font
					(size 1.27 1.27)
					(thickness 0.15)
				)
				(justify left bottom)
				(hide yes)
			)
		)
		(property "Manufacturer" "YAGEO"
			(at 359.41 81.28 0)
			(effects
				(font
					(size 1.27 1.27)
					(thickness 0.15)
				)
				(justify left bottom)
				(hide yes)
			)
		)
		(property "License" "Apache-2.0"
			(at 359.41 83.82 0)
			(effects
				(font
					(size 1.27 1.27)
					(thickness 0.15)
				)
				(justify left bottom)
				(hide yes)
			)
		)
		(property "Val" "220n"
			(at 344.932 59.944 0)
			(effects
				(font
					(size 1.27 1.27)
					(thickness 0.15)
				)
			)
		)
		(property "Voltage" ""
			(at 359.41 88.9 0)
			(effects
				(font
					(size 1.27 1.27)
				)
				(justify left bottom)
				(hide yes)
			)
		)
		(property "Dielectric" ""
			(at 359.41 91.44 0)
			(effects
				(font
					(size 1.27 1.27)
				)
				(justify left bottom)
				(hide yes)
			)
		)
		(property "Author" "Antmicro"
			(at 359.41 86.36 0)
			(effects
				(font
					(size 1.27 1.27)
					(thickness 0.15)
				)
				(justify left bottom)
				(hide yes)
			)
		)
		(pin "1"
		)
		(pin "2"
		)
		(instances
			(project "thunderbolt-to-10gbe-adapter"
				(path ""
					(reference "C46")
					(unit 1)
				)
			)
		)
	)
	(symbol
		(lib_id "antmicroResistors0402:R_100k_0402")
		(at 101.6 256.54 0)
		(unit 1)
		(exclude_from_sim no)
		(in_bom yes)
		(on_board yes)
		(dnp no)
		(property "Reference" "R52"
			(at 100.33 255.27 0)
			(effects
				(font
					(size 1.27 1.27)
					(thickness 0.15)
				)
			)
		)
		(property "Value" "R_100k_0402"
			(at 121.92 269.24 0)
			(effects
				(font
					(size 1.27 1.27)
					(thickness 0.15)
				)
				(justify left bottom)
				(hide yes)
			)
		)
		(property "Footprint" "antmicro-footprints:R_0402_1005Metric"
			(at 121.92 271.78 0)
			(effects
				(font
					(size 1.27 1.27)
					(thickness 0.15)
				)
				(justify left bottom)
				(hide yes)
			)
		)
		(property "Datasheet" "https://www.bourns.com/docs/product-datasheets/cr.pdf"
			(at 121.92 274.32 0)
			(effects
				(font
					(size 1.27 1.27)
					(thickness 0.15)
				)
				(justify left bottom)
				(hide yes)
			)
		)
		(property "Description" "SMD Chip Resistor, 100 kohm, ± 1%, 62.5 mW, 0402 [1005 Metric], Thick Film, General Purpose"
			(at 101.6 256.54 0)
			(effects
				(font
					(size 1.27 1.27)
				)
				(hide yes)
			)
		)
		(property "MPN" "CR0402-FX-1003GLF"
			(at 121.92 276.86 0)
			(effects
				(font
					(size 1.27 1.27)
					(thickness 0.15)
				)
				(justify left bottom)
				(hide yes)
			)
		)
		(property "Manufacturer" "Bourns"
			(at 121.92 279.4 0)
			(effects
				(font
					(size 1.27 1.27)
					(thickness 0.15)
				)
				(justify left bottom)
				(hide yes)
			)
		)
		(property "License" "Apache-2.0"
			(at 121.92 281.94 0)
			(effects
				(font
					(size 1.27 1.27)
					(thickness 0.15)
				)
				(justify left bottom)
				(hide yes)
			)
		)
		(property "Val" "100k"
			(at 108.585 255.27 0)
			(effects
				(font
					(size 1.27 1.27)
					(thickness 0.15)
				)
			)
		)
		(property "Tolerance" "1%"
			(at 121.92 266.7 0)
			(effects
				(font
					(size 1.27 1.27)
				)
				(justify left bottom)
				(hide yes)
			)
		)
		(property "Author" "Antmicro"
			(at 121.92 284.48 0)
			(effects
				(font
					(size 1.27 1.27)
					(thickness 0.15)
				)
				(justify left bottom)
				(hide yes)
			)
		)
		(pin "1"
		)
		(pin "2"
		)
		(instances
			(project "thunderbolt-to-10gbe-adapter"
				(path ""
					(reference "R52")
					(unit 1)
				)
			)
		)
	)
	(symbol
		(lib_id "antmicroInterfaceControllers:JHL6340SLLSQ")
		(at 341.63 182.88 0)
		(unit 6)
		(exclude_from_sim no)
		(in_bom yes)
		(on_board yes)
		(dnp no)
		(fields_autoplaced yes)
		(property "Reference" "U4"
			(at 369.57 175.26 0)
			(effects
				(font
					(size 1.27 1.27)
					(thickness 0.15)
				)
			)
		)
		(property "Value" "JHL6340SLLSQ"
			(at 412.75 185.42 0)
			(effects
				(font
					(size 1.27 1.27)
					(thickness 0.15)
				)
				(justify left bottom)
				(hide yes)
			)
		)
		(property "Footprint" "antmicro-footprints:JHL6340SLLSQ"
			(at 412.75 187.96 0)
			(effects
				(font
					(size 1.27 1.27)
					(thickness 0.15)
				)
				(justify left bottom)
				(hide yes)
			)
		)
		(property "Datasheet" "https://www.thunderbolttechnology.net/sites/default/files/18-241_ThunderboltController_Brief_HI.pdf"
			(at 412.75 190.5 0)
			(effects
				(font
					(size 1.27 1.27)
					(thickness 0.15)
				)
				(justify left bottom)
				(hide yes)
			)
		)
		(property "Description" "Thunderbolt™ 3 Controller, I/O"
			(at 341.63 182.88 0)
			(effects
				(font
					(size 1.27 1.27)
				)
				(hide yes)
			)
		)
		(property "Manufacturer" "Intel"
			(at 412.75 193.04 0)
			(effects
				(font
					(size 1.27 1.27)
					(thickness 0.15)
				)
				(justify left bottom)
				(hide yes)
			)
		)
		(property "MPN" "JHL6340SLLSQ"
			(at 369.57 177.8 0)
			(effects
				(font
					(size 1.27 1.27)
					(thickness 0.15)
				)
			)
		)
		(property "Author" "Antmicro"
			(at 412.75 198.12 0)
			(effects
				(font
					(size 1.27 1.27)
					(thickness 0.15)
				)
				(justify left bottom)
				(hide yes)
			)
		)
		(property "License" "Apache-2.0"
			(at 412.75 200.66 0)
			(effects
				(font
					(size 1.27 1.27)
					(thickness 0.15)
				)
				(justify left bottom)
				(hide yes)
			)
		)
		(pin "V5"
		)
		(pin "Y9"
		)
		(pin "AC5"
		)
		(pin "F12"
		)
		(pin "L13"
		)
		(pin "A13"
		)
		(pin "T23"
		)
		(pin "AA2"
		)
		(pin "L22"
		)
		(pin "R16"
		)
		(pin "N13"
		)
		(pin "D9"
		)
		(pin "T2"
		)
		(pin "R12"
		)
		(pin "U1"
		)
		(pin "R23"
		)
		(pin "J23"
		)
		(pin "T22"
		)
		(pin "L23"
		)
		(pin "B3"
		)
		(pin "V4"
		)
		(pin "N8"
		)
		(pin "AB11"
		)
		(pin "AB4"
		)
		(pin "M6"
		)
		(pin "K22"
		)
		(pin "R5"
		)
		(pin "L15"
		)
		(pin "F13"
		)
		(pin "L12"
		)
		(pin "H20"
		)
		(pin "V15"
		)
		(pin "V22"
		)
		(pin "V19"
		)
		(pin "P23"
		)
		(pin "M18"
		)
		(pin "A4"
		)
		(pin "A9"
		)
		(pin "M23"
		)
		(pin "Y8"
		)
		(pin "Y4"
		)
		(pin "N5"
		)
		(pin "T5"
		)
		(pin "W1"
		)
		(pin "Y11"
		)
		(pin "Y5"
		)
		(pin "B22"
		)
		(pin "B6"
		)
		(pin "V8"
		)
		(pin "V1"
		)
		(pin "A17"
		)
		(pin "Y2"
		)
		(pin "W2"
		)
		(pin "R22"
		)
		(pin "N6"
		)
		(pin "F16"
		)
		(pin "AB13"
		)
		(pin "H4"
		)
		(pin "F22"
		)
		(pin "R4"
		)
		(pin "F23"
		)
		(pin "W11"
		)
		(pin "D13"
		)
		(pin "AC10"
		)
		(pin "M9"
		)
		(pin "V2"
		)
		(pin "L19"
		)
		(pin "T18"
		)
		(pin "L20"
		)
		(pin "H8"
		)
		(pin "AB7"
		)
		(pin "Y23"
		)
		(pin "K1"
		)
		(pin "AC7"
		)
		(pin "H18"
		)
		(pin "C1"
		)
		(pin "N1"
		)
		(pin "AB5"
		)
		(pin "J5"
		)
		(pin "R15"
		)
		(pin "M13"
		)
		(pin "D1"
		)
		(pin "E20"
		)
		(pin "AC11"
		)
		(pin "A5"
		)
		(pin "AB15"
		)
		(pin "L8"
		)
		(pin "D6"
		)
		(pin "D19"
		)
		(pin "V6"
		)
		(pin "N19"
		)
		(pin "T11"
		)
		(pin "W8"
		)
		(pin "C22"
		)
		(pin "H19"
		)
		(pin "L11"
		)
		(pin "AC13"
		)
		(pin "D2"
		)
		(pin "K23"
		)
		(pin "L2"
		)
		(pin "A7"
		)
		(pin "H16"
		)
		(pin "Y16"
		)
		(pin "V12"
		)
		(pin "AB9"
		)
		(pin "M20"
		)
		(pin "N20"
		)
		(pin "R19"
		)
		(pin "U22"
		)
		(pin "AB21"
		)
		(pin "E4"
		)
		(pin "R6"
		)
		(pin "R20"
		)
		(pin "AC1"
		)
		(pin "G2"
		)
		(pin "M8"
		)
		(pin "M16"
		)
		(pin "V20"
		)
		(pin "F18"
		)
		(pin "AB3"
		)
		(pin "AA1"
		)
		(pin "D22"
		)
		(pin "V11"
		)
		(pin "T1"
		)
		(pin "V18"
		)
		(pin "B9"
		)
		(pin "J9"
		)
		(pin "M5"
		)
		(pin "H15"
		)
		(pin "M12"
		)
		(pin "M15"
		)
		(pin "AC9"
		)
		(pin "W23"
		)
		(pin "V9"
		)
		(pin "B8"
		)
		(pin "N16"
		)
		(pin "B14"
		)
		(pin "AC23"
		)
		(pin "W18"
		)
		(pin "M1"
		)
		(pin "N15"
		)
		(pin "AB17"
		)
		(pin "U23"
		)
		(pin "Y22"
		)
		(pin "L9"
		)
		(pin "T13"
		)
		(pin "F11"
		)
		(pin "N4"
		)
		(pin "F19"
		)
		(pin "W6"
		)
		(pin "F15"
		)
		(pin "B7"
		)
		(pin "Y1"
		)
		(pin "A6"
		)
		(pin "B2"
		)
		(pin "B4"
		)
		(pin "R13"
		)
		(pin "K2"
		)
		(pin "N18"
		)
		(pin "B13"
		)
		(pin "T19"
		)
		(pin "W22"
		)
		(pin "H23"
		)
		(pin "T4"
		)
		(pin "L18"
		)
		(pin "E19"
		)
		(pin "H2"
		)
		(pin "L1"
		)
		(pin "F20"
		)
		(pin "B23"
		)
		(pin "R8"
		)
		(pin "M22"
		)
		(pin "F2"
		)
		(pin "E18"
		)
		(pin "R2"
		)
		(pin "W4"
		)
		(pin "B5"
		)
		(pin "W19"
		)
		(pin "N22"
		)
		(pin "D5"
		)
		(pin "W20"
		)
		(pin "W12"
		)
		(pin "B11"
		)
		(pin "R11"
		)
		(pin "E2"
		)
		(pin "D18"
		)
		(pin "T8"
		)
		(pin "L5"
		)
		(pin "M4"
		)
		(pin "T20"
		)
		(pin "A3"
		)
		(pin "AC3"
		)
		(pin "A19"
		)
		(pin "L16"
		)
		(pin "F4"
		)
		(pin "T12"
		)
		(pin "Y18"
		)
		(pin "T16"
		)
		(pin "AB19"
		)
		(pin "B12"
		)
		(pin "E23"
		)
		(pin "E1"
		)
		(pin "T6"
		)
		(pin "Y19"
		)
		(pin "T15"
		)
		(pin "P22"
		)
		(pin "AB16"
		)
		(pin "AC4"
		)
		(pin "D15"
		)
		(pin "G1"
		)
		(pin "A8"
		)
		(pin "Y12"
		)
		(pin "J4"
		)
		(pin "J1"
		)
		(pin "E22"
		)
		(pin "D20"
		)
		(pin "M2"
		)
		(pin "V23"
		)
		(pin "AB10"
		)
		(pin "AB2"
		)
		(pin "AC15"
		)
		(pin "D23"
		)
		(pin "A23"
		)
		(pin "C23"
		)
		(pin "J2"
		)
		(pin "A21"
		)
		(pin "F1"
		)
		(pin "H5"
		)
		(pin "N11"
		)
		(pin "B20"
		)
		(pin "H22"
		)
		(pin "AA23"
		)
		(pin "E13"
		)
		(pin "J12"
		)
		(pin "W9"
		)
		(pin "H9"
		)
		(pin "B19"
		)
		(pin "AB8"
		)
		(pin "AB22"
		)
		(pin "AB6"
		)
		(pin "AB20"
		)
		(pin "AC2"
		)
		(pin "E9"
		)
		(pin "J11"
		)
		(pin "L4"
		)
		(pin "J8"
		)
		(pin "AC22"
		)
		(pin "J13"
		)
		(pin "N12"
		)
		(pin "J15"
		)
		(pin "B18"
		)
		(pin "Y15"
		)
		(pin "U2"
		)
		(pin "AC12"
		)
		(pin "D16"
		)
		(pin "AB14"
		)
		(pin "AC6"
		)
		(pin "A14"
		)
		(pin "V13"
		)
		(pin "G22"
		)
		(pin "Y13"
		)
		(pin "B16"
		)
		(pin "AB18"
		)
		(pin "B17"
		)
		(pin "A20"
		)
		(pin "AB12"
		)
		(pin "R1"
		)
		(pin "AC20"
		)
		(pin "H12"
		)
		(pin "A2"
		)
		(pin "F5"
		)
		(pin "E6"
		)
		(pin "A10"
		)
		(pin "A12"
		)
		(pin "H11"
		)
		(pin "F9"
		)
		(pin "A1"
		)
		(pin "AB1"
		)
		(pin "E8"
		)
		(pin "A11"
		)
		(pin "L6"
		)
		(pin "B21"
		)
		(pin "AB23"
		)
		(pin "W13"
		)
		(pin "P2"
		)
		(pin "W16"
		)
		(pin "AC16"
		)
		(pin "H6"
		)
		(pin "Y6"
		)
		(pin "A15"
		)
		(pin "J6"
		)
		(pin "V16"
		)
		(pin "N9"
		)
		(pin "AC21"
		)
		(pin "J19"
		)
		(pin "J20"
		)
		(pin "AC17"
		)
		(pin "AC19"
		)
		(pin "M11"
		)
		(pin "D4"
		)
		(pin "P1"
		)
		(pin "W5"
		)
		(pin "R18"
		)
		(pin "E16"
		)
		(pin "N23"
		)
		(pin "A22"
		)
		(pin "R9"
		)
		(pin "D8"
		)
		(pin "E15"
		)
		(pin "M19"
		)
		(pin "Y20"
		)
		(pin "T9"
		)
		(pin "H13"
		)
		(pin "W15"
		)
		(pin "B10"
		)
		(pin "AC14"
		)
		(pin "AC18"
		)
		(pin "C2"
		)
		(pin "E5"
		)
		(pin "J22"
		)
		(pin "J18"
		)
		(pin "J16"
		)
		(pin "AC8"
		)
		(pin "B1"
		)
		(pin "N2"
		)
		(pin "E11"
		)
		(pin "A18"
		)
		(pin "H1"
		)
		(pin "G23"
		)
		(pin "A16"
		)
		(pin "D11"
		)
		(pin "B15"
		)
		(pin "F8"
		)
		(pin "E12"
		)
		(pin "AA22"
		)
		(pin "D12"
		)
		(pin "F6"
		)
		(instances
			(project "thunderbolt-to-10gbe-adapter"
				(path ""
					(reference "U4")
					(unit 6)
				)
			)
		)
	)
	(symbol
		(lib_id "antmicroCapacitors0402:C_220n_0402")
		(at 339.09 53.34 0)
		(unit 1)
		(exclude_from_sim no)
		(in_bom yes)
		(on_board yes)
		(dnp no)
		(property "Reference" "C45"
			(at 338.328 52.324 0)
			(effects
				(font
					(size 1.27 1.27)
					(thickness 0.15)
				)
			)
		)
		(property "Value" "C_220n_0402"
			(at 359.41 63.5 0)
			(effects
				(font
					(size 1.27 1.27)
					(thickness 0.15)
				)
				(justify left bottom)
				(hide yes)
			)
		)
		(property "Footprint" "antmicro-footprints:C_0402_1005Metric"
			(at 359.41 66.04 0)
			(effects
				(font
					(size 1.27 1.27)
					(thickness 0.15)
				)
				(justify left bottom)
				(hide yes)
			)
		)
		(property "Datasheet" "https://www.yageo.com/en/Chart/Download/pdf/CC0402KRX5R6BB224"
			(at 359.41 68.58 0)
			(effects
				(font
					(size 1.27 1.27)
					(thickness 0.15)
				)
				(justify left bottom)
				(hide yes)
			)
		)
		(property "Description" "SMD Multilayer Ceramic Capacitor, 0.22 µF, 10 V, 0402 [1005 Metric], ± 10%, X5R, CC Series"
			(at 339.09 53.34 0)
			(effects
				(font
					(size 1.27 1.27)
				)
				(hide yes)
			)
		)
		(property "MPN" "CC0402KRX5R6BB224"
			(at 359.41 71.12 0)
			(effects
				(font
					(size 1.27 1.27)
					(thickness 0.15)
				)
				(justify left bottom)
				(hide yes)
			)
		)
		(property "Manufacturer" "YAGEO"
			(at 359.41 73.66 0)
			(effects
				(font
					(size 1.27 1.27)
					(thickness 0.15)
				)
				(justify left bottom)
				(hide yes)
			)
		)
		(property "License" "Apache-2.0"
			(at 359.41 76.2 0)
			(effects
				(font
					(size 1.27 1.27)
					(thickness 0.15)
				)
				(justify left bottom)
				(hide yes)
			)
		)
		(property "Val" "220n"
			(at 344.932 52.324 0)
			(effects
				(font
					(size 1.27 1.27)
					(thickness 0.15)
				)
			)
		)
		(property "Voltage" ""
			(at 359.41 81.28 0)
			(effects
				(font
					(size 1.27 1.27)
				)
				(justify left bottom)
				(hide yes)
			)
		)
		(property "Dielectric" ""
			(at 359.41 83.82 0)
			(effects
				(font
					(size 1.27 1.27)
				)
				(justify left bottom)
				(hide yes)
			)
		)
		(property "Author" "Antmicro"
			(at 359.41 78.74 0)
			(effects
				(font
					(size 1.27 1.27)
					(thickness 0.15)
				)
				(justify left bottom)
				(hide yes)
			)
		)
		(pin "1"
		)
		(pin "2"
		)
		(instances
			(project "thunderbolt-to-10gbe-adapter"
				(path ""
					(reference "C45")
					(unit 1)
				)
			)
		)
	)
	(symbol
		(lib_id "antmicroResistors0402:R_10k_0402")
		(at 189.23 186.69 0)
		(unit 1)
		(exclude_from_sim no)
		(in_bom yes)
		(on_board yes)
		(dnp no)
		(property "Reference" "R63"
			(at 195.58 185.42 0)
			(effects
				(font
					(size 1.27 1.27)
					(thickness 0.15)
				)
			)
		)
		(property "Value" "R_10k_0402"
			(at 209.55 199.39 0)
			(effects
				(font
					(size 1.27 1.27)
					(thickness 0.15)
				)
				(justify left bottom)
				(hide yes)
			)
		)
		(property "Footprint" "antmicro-footprints:R_0402_1005Metric"
			(at 209.55 201.93 0)
			(effects
				(font
					(size 1.27 1.27)
					(thickness 0.15)
				)
				(justify left bottom)
				(hide yes)
			)
		)
		(property "Datasheet" "https://www.bourns.com/docs/product-datasheets/cr.pdf"
			(at 209.55 204.47 0)
			(effects
				(font
					(size 1.27 1.27)
					(thickness 0.15)
				)
				(justify left bottom)
				(hide yes)
			)
		)
		(property "Description" "SMD Chip Resistor, 10 kohm, ± 1%, 62.5 mW, 0402 [1005 Metric], Thick Film, General Purpose"
			(at 189.23 186.69 0)
			(effects
				(font
					(size 1.27 1.27)
				)
				(hide yes)
			)
		)
		(property "MPN" "CR0402-FX-1002GLF"
			(at 209.55 207.01 0)
			(effects
				(font
					(size 1.27 1.27)
					(thickness 0.15)
				)
				(justify left bottom)
				(hide yes)
			)
		)
		(property "Manufacturer" "Bourns"
			(at 209.55 209.55 0)
			(effects
				(font
					(size 1.27 1.27)
					(thickness 0.15)
				)
				(justify left bottom)
				(hide yes)
			)
		)
		(property "License" "Apache-2.0"
			(at 209.55 212.09 0)
			(effects
				(font
					(size 1.27 1.27)
					(thickness 0.15)
				)
				(justify left bottom)
				(hide yes)
			)
		)
		(property "Val" "10k"
			(at 187.96 185.42 0)
			(effects
				(font
					(size 1.27 1.27)
					(thickness 0.15)
				)
			)
		)
		(property "Tolerance" "1%"
			(at 209.55 196.85 0)
			(effects
				(font
					(size 1.27 1.27)
				)
				(justify left bottom)
				(hide yes)
			)
		)
		(property "Author" "Antmicro"
			(at 209.55 214.63 0)
			(effects
				(font
					(size 1.27 1.27)
					(thickness 0.15)
				)
				(justify left bottom)
				(hide yes)
			)
		)
		(pin "1"
		)
		(pin "2"
		)
		(instances
			(project "thunderbolt-to-10gbe-adapter"
				(path ""
					(reference "R63")
					(unit 1)
				)
			)
		)
	)
	(symbol
		(lib_id "antmicroResistors0402:R_100k_0402")
		(at 185.42 96.52 0)
		(unit 1)
		(exclude_from_sim no)
		(in_bom yes)
		(on_board yes)
		(dnp no)
		(property "Reference" "R60"
			(at 184.15 95.25 0)
			(effects
				(font
					(size 1.27 1.27)
					(thickness 0.15)
				)
			)
		)
		(property "Value" "R_100k_0402"
			(at 205.74 109.22 0)
			(effects
				(font
					(size 1.27 1.27)
					(thickness 0.15)
				)
				(justify left bottom)
				(hide yes)
			)
		)
		(property "Footprint" "antmicro-footprints:R_0402_1005Metric"
			(at 205.74 111.76 0)
			(effects
				(font
					(size 1.27 1.27)
					(thickness 0.15)
				)
				(justify left bottom)
				(hide yes)
			)
		)
		(property "Datasheet" "https://www.bourns.com/docs/product-datasheets/cr.pdf"
			(at 205.74 114.3 0)
			(effects
				(font
					(size 1.27 1.27)
					(thickness 0.15)
				)
				(justify left bottom)
				(hide yes)
			)
		)
		(property "Description" "SMD Chip Resistor, 100 kohm, ± 1%, 62.5 mW, 0402 [1005 Metric], Thick Film, General Purpose"
			(at 185.42 96.52 0)
			(effects
				(font
					(size 1.27 1.27)
				)
				(hide yes)
			)
		)
		(property "MPN" "CR0402-FX-1003GLF"
			(at 205.74 116.84 0)
			(effects
				(font
					(size 1.27 1.27)
					(thickness 0.15)
				)
				(justify left bottom)
				(hide yes)
			)
		)
		(property "Manufacturer" "Bourns"
			(at 205.74 119.38 0)
			(effects
				(font
					(size 1.27 1.27)
					(thickness 0.15)
				)
				(justify left bottom)
				(hide yes)
			)
		)
		(property "License" "Apache-2.0"
			(at 205.74 121.92 0)
			(effects
				(font
					(size 1.27 1.27)
					(thickness 0.15)
				)
				(justify left bottom)
				(hide yes)
			)
		)
		(property "Val" "100k"
			(at 193.04 95.25 0)
			(effects
				(font
					(size 1.27 1.27)
					(thickness 0.15)
				)
			)
		)
		(property "Tolerance" "1%"
			(at 205.74 106.68 0)
			(effects
				(font
					(size 1.27 1.27)
				)
				(justify left bottom)
				(hide yes)
			)
		)
		(property "Author" "Antmicro"
			(at 205.74 124.46 0)
			(effects
				(font
					(size 1.27 1.27)
					(thickness 0.15)
				)
				(justify left bottom)
				(hide yes)
			)
		)
		(pin "1"
		)
		(pin "2"
		)
		(instances
			(project "thunderbolt-to-10gbe-adapter"
				(path ""
					(reference "R60")
					(unit 1)
				)
			)
		)
	)
	(symbol
		(lib_id "antmicroResistors0402:R_499R_0402")
		(at 185.42 101.6 0)
		(unit 1)
		(exclude_from_sim no)
		(in_bom yes)
		(on_board yes)
		(dnp no)
		(property "Reference" "R61"
			(at 184.15 100.33 0)
			(effects
				(font
					(size 1.27 1.27)
					(thickness 0.15)
				)
			)
		)
		(property "Value" "R_499R_0402"
			(at 205.74 114.3 0)
			(effects
				(font
					(size 1.27 1.27)
					(thickness 0.15)
				)
				(justify left bottom)
				(hide yes)
			)
		)
		(property "Footprint" "antmicro-footprints:R_0402_1005Metric"
			(at 205.74 116.84 0)
			(effects
				(font
					(size 1.27 1.27)
					(thickness 0.15)
				)
				(justify left bottom)
				(hide yes)
			)
		)
		(property "Datasheet" "https://www.mouser.com/datasheet/2/54/cr-1858361.pdf"
			(at 205.74 119.38 0)
			(effects
				(font
					(size 1.27 1.27)
					(thickness 0.15)
				)
				(justify left bottom)
				(hide yes)
			)
		)
		(property "Description" "SMD Chip Resistor, 499 ohm, ± 1%, 63 mW, 0402 [1005 Metric], Thick Film, General Purpose"
			(at 185.42 101.6 0)
			(effects
				(font
					(size 1.27 1.27)
				)
				(hide yes)
			)
		)
		(property "MPN" "CR0402-FX-4990GLF"
			(at 205.74 121.92 0)
			(effects
				(font
					(size 1.27 1.27)
					(thickness 0.15)
				)
				(justify left bottom)
				(hide yes)
			)
		)
		(property "Manufacturer" "Bourns"
			(at 205.74 124.46 0)
			(effects
				(font
					(size 1.27 1.27)
					(thickness 0.15)
				)
				(justify left bottom)
				(hide yes)
			)
		)
		(property "License" "Apache-2.0"
			(at 205.74 127 0)
			(effects
				(font
					(size 1.27 1.27)
					(thickness 0.15)
				)
				(justify left bottom)
				(hide yes)
			)
		)
		(property "Val" "499R"
			(at 193.04 100.33 0)
			(effects
				(font
					(size 1.27 1.27)
					(thickness 0.15)
				)
			)
		)
		(property "Tolerance" "1%"
			(at 205.74 111.76 0)
			(effects
				(font
					(size 1.27 1.27)
				)
				(justify left bottom)
				(hide yes)
			)
		)
		(property "Author" "Antmicro"
			(at 205.74 129.54 0)
			(effects
				(font
					(size 1.27 1.27)
					(thickness 0.15)
				)
				(justify left bottom)
				(hide yes)
			)
		)
		(pin "1"
		)
		(pin "2"
		)
		(instances
			(project "thunderbolt-to-10gbe-adapter"
				(path ""
					(reference "R61")
					(unit 1)
				)
			)
		)
	)
	(symbol
		(lib_id "antmicropower:GND")
		(at 271.78 116.84 0)
		(unit 1)
		(exclude_from_sim no)
		(in_bom yes)
		(on_board yes)
		(dnp no)
		(property "Reference" "#PWR073"
			(at 271.78 123.19 0)
			(effects
				(font
					(size 1.27 1.27)
				)
				(hide yes)
			)
		)
		(property "Value" "GND"
			(at 271.78 120.65 0)
			(effects
				(font
					(size 1.27 1.27)
				)
			)
		)
		(property "Footprint" ""
			(at 271.78 116.84 0)
			(effects
				(font
					(size 1.27 1.27)
				)
				(hide yes)
			)
		)
		(property "Datasheet" ""
			(at 271.78 116.84 0)
			(effects
				(font
					(size 1.27 1.27)
				)
				(hide yes)
			)
		)
		(property "Description" ""
			(at 271.78 116.84 0)
			(effects
				(font
					(size 1.27 1.27)
				)
				(hide yes)
			)
		)
		(property "Author" "Antmicro"
			(at 280.67 124.46 0)
			(effects
				(font
					(size 1.27 1.27)
					(thickness 0.15)
				)
				(justify left bottom)
				(hide yes)
			)
		)
		(property "License" "Apache-2.0"
			(at 280.67 127 0)
			(effects
				(font
					(size 1.27 1.27)
					(thickness 0.15)
				)
				(justify left bottom)
				(hide yes)
			)
		)
		(pin "1"
		)
		(instances
			(project "thunderbolt-to-10gbe-adapter"
				(path ""
					(reference "#PWR073")
					(unit 1)
				)
			)
		)
	)
	(symbol
		(lib_id "antmicroInterfaceControllers:JHL6340SLLSQ")
		(at 127 45.72 0)
		(unit 5)
		(exclude_from_sim no)
		(in_bom yes)
		(on_board yes)
		(dnp no)
		(fields_autoplaced yes)
		(property "Reference" "U4"
			(at 154.94 37.465 0)
			(effects
				(font
					(size 1.27 1.27)
					(thickness 0.15)
				)
			)
		)
		(property "Value" "JHL6340SLLSQ"
			(at 198.12 48.26 0)
			(effects
				(font
					(size 1.27 1.27)
					(thickness 0.15)
				)
				(justify left bottom)
				(hide yes)
			)
		)
		(property "Footprint" "antmicro-footprints:JHL6340SLLSQ"
			(at 198.12 50.8 0)
			(effects
				(font
					(size 1.27 1.27)
					(thickness 0.15)
				)
				(justify left bottom)
				(hide yes)
			)
		)
		(property "Datasheet" "https://www.thunderbolttechnology.net/sites/default/files/18-241_ThunderboltController_Brief_HI.pdf"
			(at 198.12 53.34 0)
			(effects
				(font
					(size 1.27 1.27)
					(thickness 0.15)
				)
				(justify left bottom)
				(hide yes)
			)
		)
		(property "Description" "Thunderbolt™ 3 Controller, I/O"
			(at 127 45.72 0)
			(effects
				(font
					(size 1.27 1.27)
				)
				(hide yes)
			)
		)
		(property "Manufacturer" "Intel"
			(at 198.12 55.88 0)
			(effects
				(font
					(size 1.27 1.27)
					(thickness 0.15)
				)
				(justify left bottom)
				(hide yes)
			)
		)
		(property "MPN" "JHL6340SLLSQ"
			(at 154.94 40.005 0)
			(effects
				(font
					(size 1.27 1.27)
					(thickness 0.15)
				)
			)
		)
		(property "Author" "Antmicro"
			(at 198.12 60.96 0)
			(effects
				(font
					(size 1.27 1.27)
					(thickness 0.15)
				)
				(justify left bottom)
				(hide yes)
			)
		)
		(property "License" "Apache-2.0"
			(at 198.12 63.5 0)
			(effects
				(font
					(size 1.27 1.27)
					(thickness 0.15)
				)
				(justify left bottom)
				(hide yes)
			)
		)
		(pin "V5"
		)
		(pin "Y9"
		)
		(pin "AC5"
		)
		(pin "F12"
		)
		(pin "L13"
		)
		(pin "A13"
		)
		(pin "T23"
		)
		(pin "AA2"
		)
		(pin "L22"
		)
		(pin "R16"
		)
		(pin "N13"
		)
		(pin "D9"
		)
		(pin "T2"
		)
		(pin "R12"
		)
		(pin "U1"
		)
		(pin "R23"
		)
		(pin "J23"
		)
		(pin "T22"
		)
		(pin "L23"
		)
		(pin "B3"
		)
		(pin "V4"
		)
		(pin "N8"
		)
		(pin "AB11"
		)
		(pin "AB4"
		)
		(pin "M6"
		)
		(pin "K22"
		)
		(pin "R5"
		)
		(pin "L15"
		)
		(pin "F13"
		)
		(pin "L12"
		)
		(pin "H20"
		)
		(pin "V15"
		)
		(pin "V22"
		)
		(pin "V19"
		)
		(pin "P23"
		)
		(pin "M18"
		)
		(pin "A4"
		)
		(pin "A9"
		)
		(pin "M23"
		)
		(pin "Y8"
		)
		(pin "Y4"
		)
		(pin "N5"
		)
		(pin "T5"
		)
		(pin "W1"
		)
		(pin "Y11"
		)
		(pin "Y5"
		)
		(pin "B22"
		)
		(pin "B6"
		)
		(pin "V8"
		)
		(pin "V1"
		)
		(pin "A17"
		)
		(pin "Y2"
		)
		(pin "W2"
		)
		(pin "R22"
		)
		(pin "N6"
		)
		(pin "F16"
		)
		(pin "AB13"
		)
		(pin "H4"
		)
		(pin "F22"
		)
		(pin "R4"
		)
		(pin "F23"
		)
		(pin "W11"
		)
		(pin "D13"
		)
		(pin "AC10"
		)
		(pin "M9"
		)
		(pin "V2"
		)
		(pin "L19"
		)
		(pin "T18"
		)
		(pin "L20"
		)
		(pin "H8"
		)
		(pin "AB7"
		)
		(pin "Y23"
		)
		(pin "K1"
		)
		(pin "AC7"
		)
		(pin "H18"
		)
		(pin "C1"
		)
		(pin "N1"
		)
		(pin "AB5"
		)
		(pin "J5"
		)
		(pin "R15"
		)
		(pin "M13"
		)
		(pin "D1"
		)
		(pin "E20"
		)
		(pin "AC11"
		)
		(pin "A5"
		)
		(pin "AB15"
		)
		(pin "L8"
		)
		(pin "D6"
		)
		(pin "D19"
		)
		(pin "V6"
		)
		(pin "N19"
		)
		(pin "T11"
		)
		(pin "W8"
		)
		(pin "C22"
		)
		(pin "H19"
		)
		(pin "L11"
		)
		(pin "AC13"
		)
		(pin "D2"
		)
		(pin "K23"
		)
		(pin "L2"
		)
		(pin "A7"
		)
		(pin "H16"
		)
		(pin "Y16"
		)
		(pin "V12"
		)
		(pin "AB9"
		)
		(pin "M20"
		)
		(pin "N20"
		)
		(pin "R19"
		)
		(pin "U22"
		)
		(pin "AB21"
		)
		(pin "E4"
		)
		(pin "R6"
		)
		(pin "R20"
		)
		(pin "AC1"
		)
		(pin "G2"
		)
		(pin "M8"
		)
		(pin "M16"
		)
		(pin "V20"
		)
		(pin "F18"
		)
		(pin "AB3"
		)
		(pin "AA1"
		)
		(pin "D22"
		)
		(pin "V11"
		)
		(pin "T1"
		)
		(pin "V18"
		)
		(pin "B9"
		)
		(pin "J9"
		)
		(pin "M5"
		)
		(pin "H15"
		)
		(pin "M12"
		)
		(pin "M15"
		)
		(pin "AC9"
		)
		(pin "W23"
		)
		(pin "V9"
		)
		(pin "B8"
		)
		(pin "N16"
		)
		(pin "B14"
		)
		(pin "AC23"
		)
		(pin "W18"
		)
		(pin "M1"
		)
		(pin "N15"
		)
		(pin "AB17"
		)
		(pin "U23"
		)
		(pin "Y22"
		)
		(pin "L9"
		)
		(pin "T13"
		)
		(pin "F11"
		)
		(pin "N4"
		)
		(pin "F19"
		)
		(pin "W6"
		)
		(pin "F15"
		)
		(pin "B7"
		)
		(pin "Y1"
		)
		(pin "A6"
		)
		(pin "B2"
		)
		(pin "B4"
		)
		(pin "R13"
		)
		(pin "K2"
		)
		(pin "N18"
		)
		(pin "B13"
		)
		(pin "T19"
		)
		(pin "W22"
		)
		(pin "H23"
		)
		(pin "T4"
		)
		(pin "L18"
		)
		(pin "E19"
		)
		(pin "H2"
		)
		(pin "L1"
		)
		(pin "F20"
		)
		(pin "B23"
		)
		(pin "R8"
		)
		(pin "M22"
		)
		(pin "F2"
		)
		(pin "E18"
		)
		(pin "R2"
		)
		(pin "W4"
		)
		(pin "B5"
		)
		(pin "W19"
		)
		(pin "N22"
		)
		(pin "D5"
		)
		(pin "W20"
		)
		(pin "W12"
		)
		(pin "B11"
		)
		(pin "R11"
		)
		(pin "E2"
		)
		(pin "D18"
		)
		(pin "T8"
		)
		(pin "L5"
		)
		(pin "M4"
		)
		(pin "T20"
		)
		(pin "A3"
		)
		(pin "AC3"
		)
		(pin "A19"
		)
		(pin "L16"
		)
		(pin "F4"
		)
		(pin "T12"
		)
		(pin "Y18"
		)
		(pin "T16"
		)
		(pin "AB19"
		)
		(pin "B12"
		)
		(pin "E23"
		)
		(pin "E1"
		)
		(pin "T6"
		)
		(pin "Y19"
		)
		(pin "T15"
		)
		(pin "P22"
		)
		(pin "AB16"
		)
		(pin "AC4"
		)
		(pin "D15"
		)
		(pin "G1"
		)
		(pin "A8"
		)
		(pin "Y12"
		)
		(pin "J4"
		)
		(pin "J1"
		)
		(pin "E22"
		)
		(pin "D20"
		)
		(pin "M2"
		)
		(pin "V23"
		)
		(pin "AB10"
		)
		(pin "AB2"
		)
		(pin "AC15"
		)
		(pin "D23"
		)
		(pin "A23"
		)
		(pin "C23"
		)
		(pin "J2"
		)
		(pin "A21"
		)
		(pin "F1"
		)
		(pin "H5"
		)
		(pin "N11"
		)
		(pin "B20"
		)
		(pin "H22"
		)
		(pin "AA23"
		)
		(pin "E13"
		)
		(pin "J12"
		)
		(pin "W9"
		)
		(pin "H9"
		)
		(pin "B19"
		)
		(pin "AB8"
		)
		(pin "AB22"
		)
		(pin "AB6"
		)
		(pin "AB20"
		)
		(pin "AC2"
		)
		(pin "E9"
		)
		(pin "J11"
		)
		(pin "L4"
		)
		(pin "J8"
		)
		(pin "AC22"
		)
		(pin "J13"
		)
		(pin "N12"
		)
		(pin "J15"
		)
		(pin "B18"
		)
		(pin "Y15"
		)
		(pin "U2"
		)
		(pin "AC12"
		)
		(pin "D16"
		)
		(pin "AB14"
		)
		(pin "AC6"
		)
		(pin "A14"
		)
		(pin "V13"
		)
		(pin "G22"
		)
		(pin "Y13"
		)
		(pin "B16"
		)
		(pin "AB18"
		)
		(pin "B17"
		)
		(pin "A20"
		)
		(pin "AB12"
		)
		(pin "R1"
		)
		(pin "AC20"
		)
		(pin "H12"
		)
		(pin "A2"
		)
		(pin "F5"
		)
		(pin "E6"
		)
		(pin "A10"
		)
		(pin "A12"
		)
		(pin "H11"
		)
		(pin "F9"
		)
		(pin "A1"
		)
		(pin "AB1"
		)
		(pin "E8"
		)
		(pin "A11"
		)
		(pin "L6"
		)
		(pin "B21"
		)
		(pin "AB23"
		)
		(pin "W13"
		)
		(pin "P2"
		)
		(pin "W16"
		)
		(pin "AC16"
		)
		(pin "H6"
		)
		(pin "Y6"
		)
		(pin "A15"
		)
		(pin "J6"
		)
		(pin "V16"
		)
		(pin "N9"
		)
		(pin "AC21"
		)
		(pin "J19"
		)
		(pin "J20"
		)
		(pin "AC17"
		)
		(pin "AC19"
		)
		(pin "M11"
		)
		(pin "D4"
		)
		(pin "P1"
		)
		(pin "W5"
		)
		(pin "R18"
		)
		(pin "E16"
		)
		(pin "N23"
		)
		(pin "A22"
		)
		(pin "R9"
		)
		(pin "D8"
		)
		(pin "E15"
		)
		(pin "M19"
		)
		(pin "Y20"
		)
		(pin "T9"
		)
		(pin "H13"
		)
		(pin "W15"
		)
		(pin "B10"
		)
		(pin "AC14"
		)
		(pin "AC18"
		)
		(pin "C2"
		)
		(pin "E5"
		)
		(pin "J22"
		)
		(pin "J18"
		)
		(pin "J16"
		)
		(pin "AC8"
		)
		(pin "B1"
		)
		(pin "N2"
		)
		(pin "E11"
		)
		(pin "A18"
		)
		(pin "H1"
		)
		(pin "G23"
		)
		(pin "A16"
		)
		(pin "D11"
		)
		(pin "B15"
		)
		(pin "F8"
		)
		(pin "E12"
		)
		(pin "AA22"
		)
		(pin "D12"
		)
		(pin "F6"
		)
		(instances
			(project "thunderbolt-to-10gbe-adapter"
				(path ""
					(reference "U4")
					(unit 5)
				)
			)
		)
	)
	(symbol
		(lib_id "antmicropower:+3V3")
		(at 252.73 83.82 0)
		(unit 1)
		(exclude_from_sim no)
		(in_bom yes)
		(on_board yes)
		(dnp no)
		(property "Reference" "#PWR070"
			(at 267.97 83.82 0)
			(effects
				(font
					(size 1.27 1.27)
					(thickness 0.15)
				)
				(justify left bottom)
				(hide yes)
			)
		)
		(property "Value" "+3V3_TB"
			(at 252.73 80.01 0)
			(effects
				(font
					(size 1.27 1.27)
					(thickness 0.15)
				)
			)
		)
		(property "Footprint" ""
			(at 267.97 91.44 0)
			(effects
				(font
					(size 1.27 1.27)
					(thickness 0.15)
				)
				(justify left bottom)
				(hide yes)
			)
		)
		(property "Datasheet" ""
			(at 267.97 93.98 0)
			(effects
				(font
					(size 1.27 1.27)
					(thickness 0.15)
				)
				(justify left bottom)
				(hide yes)
			)
		)
		(property "Description" ""
			(at 267.97 96.52 0)
			(effects
				(font
					(size 1.27 1.27)
				)
				(justify left bottom)
				(hide yes)
			)
		)
		(property "Author" "Antmicro"
			(at 267.97 86.36 0)
			(effects
				(font
					(size 1.27 1.27)
					(thickness 0.15)
				)
				(justify left bottom)
				(hide yes)
			)
		)
		(property "License" "Apache-2.0"
			(at 267.97 88.9 0)
			(effects
				(font
					(size 1.27 1.27)
					(thickness 0.15)
				)
				(justify left bottom)
				(hide yes)
			)
		)
		(pin "1"
		)
		(instances
			(project "thunderbolt-to-10gbe-adapter"
				(path ""
					(reference "#PWR070")
					(unit 1)
				)
			)
		)
	)
	(symbol
		(lib_id "antmicropower:GND")
		(at 340.36 213.36 0)
		(unit 1)
		(exclude_from_sim no)
		(in_bom yes)
		(on_board yes)
		(dnp no)
		(property "Reference" "#PWR078"
			(at 340.36 219.71 0)
			(effects
				(font
					(size 1.27 1.27)
				)
				(hide yes)
			)
		)
		(property "Value" "GND"
			(at 340.36 217.17 0)
			(effects
				(font
					(size 1.27 1.27)
				)
			)
		)
		(property "Footprint" ""
			(at 340.36 213.36 0)
			(effects
				(font
					(size 1.27 1.27)
				)
				(hide yes)
			)
		)
		(property "Datasheet" ""
			(at 340.36 213.36 0)
			(effects
				(font
					(size 1.27 1.27)
				)
				(hide yes)
			)
		)
		(property "Description" ""
			(at 340.36 213.36 0)
			(effects
				(font
					(size 1.27 1.27)
				)
				(hide yes)
			)
		)
		(property "Author" "Antmicro"
			(at 349.25 220.98 0)
			(effects
				(font
					(size 1.27 1.27)
					(thickness 0.15)
				)
				(justify left bottom)
				(hide yes)
			)
		)
		(property "License" "Apache-2.0"
			(at 349.25 223.52 0)
			(effects
				(font
					(size 1.27 1.27)
					(thickness 0.15)
				)
				(justify left bottom)
				(hide yes)
			)
		)
		(pin "1"
		)
		(instances
			(project "thunderbolt-to-10gbe-adapter"
				(path ""
					(reference "#PWR078")
					(unit 1)
				)
			)
		)
	)
	(symbol
		(lib_id "antmicroCapacitors0402:C_10p_0402")
		(at 246.38 128.27 0)
		(unit 1)
		(exclude_from_sim no)
		(in_bom yes)
		(on_board yes)
		(dnp no)
		(fields_autoplaced yes)
		(property "Reference" "C40"
			(at 248.9263 132.08 0)
			(effects
				(font
					(size 1.27 1.27)
					(thickness 0.15)
				)
			)
		)
		(property "Value" "C_10p_0402"
			(at 266.7 138.43 0)
			(effects
				(font
					(size 1.27 1.27)
					(thickness 0.15)
				)
				(justify left bottom)
				(hide yes)
			)
		)
		(property "Footprint" "antmicro-footprints:C_0402_1005Metric"
			(at 266.7 140.97 0)
			(effects
				(font
					(size 1.27 1.27)
					(thickness 0.15)
				)
				(justify left bottom)
				(hide yes)
			)
		)
		(property "Datasheet" "https://www.murata.com/products/productdetail?partno=GCM1555C1H100GA16%23"
			(at 266.7 143.51 0)
			(effects
				(font
					(size 1.27 1.27)
					(thickness 0.15)
				)
				(justify left bottom)
				(hide yes)
			)
		)
		(property "Description" "SMD Multilayer Ceramic Capacitor, 10 pF, 50 V, 0402 [1005 Metric], ± 2%, C0G / NP0, GCM"
			(at 246.38 128.27 0)
			(effects
				(font
					(size 1.27 1.27)
				)
				(hide yes)
			)
		)
		(property "MPN" "GCM1555C1H100GA16D"
			(at 266.7 146.05 0)
			(effects
				(font
					(size 1.27 1.27)
					(thickness 0.15)
				)
				(justify left bottom)
				(hide yes)
			)
		)
		(property "Manufacturer" "Murata"
			(at 266.7 148.59 0)
			(effects
				(font
					(size 1.27 1.27)
					(thickness 0.15)
				)
				(justify left bottom)
				(hide yes)
			)
		)
		(property "License" "Apache-2.0"
			(at 266.7 151.13 0)
			(effects
				(font
					(size 1.27 1.27)
					(thickness 0.15)
				)
				(justify left bottom)
				(hide yes)
			)
		)
		(property "Val" "10p"
			(at 248.9263 134.62 0)
			(effects
				(font
					(size 1.27 1.27)
					(thickness 0.15)
				)
			)
		)
		(property "Voltage" "50V"
			(at 266.7 156.21 0)
			(effects
				(font
					(size 1.27 1.27)
				)
				(justify left bottom)
				(hide yes)
			)
		)
		(property "Dielectric" "C0G"
			(at 266.7 158.75 0)
			(effects
				(font
					(size 1.27 1.27)
				)
				(justify left bottom)
				(hide yes)
			)
		)
		(property "Author" "Antmicro"
			(at 266.7 153.67 0)
			(effects
				(font
					(size 1.27 1.27)
					(thickness 0.15)
				)
				(justify left bottom)
				(hide yes)
			)
		)
		(pin "1"
		)
		(pin "2"
		)
		(instances
			(project "thunderbolt-to-10gbe-adapter"
				(path ""
					(reference "C40")
					(unit 1)
				)
			)
		)
	)
	(symbol
		(lib_id "antmicroCapacitors0402:C_100n_0402")
		(at 271.78 114.3 90)
		(unit 1)
		(exclude_from_sim no)
		(in_bom yes)
		(on_board yes)
		(dnp no)
		(fields_autoplaced yes)
		(property "Reference" "C41"
			(at 268.605 110.4836 90)
			(effects
				(font
					(size 1.27 1.27)
					(thickness 0.15)
				)
				(justify left)
			)
		)
		(property "Value" "C_100n_0402"
			(at 281.94 93.98 0)
			(effects
				(font
					(size 1.27 1.27)
					(thickness 0.15)
				)
				(justify left bottom)
				(hide yes)
			)
		)
		(property "Footprint" "antmicro-footprints:C_0402_1005Metric"
			(at 284.48 93.98 0)
			(effects
				(font
					(size 1.27 1.27)
					(thickness 0.15)
				)
				(justify left bottom)
				(hide yes)
			)
		)
		(property "Datasheet" "https://www.murata.com/products/productdetail?partno=GRM155R61H104KE14%23"
			(at 287.02 93.98 0)
			(effects
				(font
					(size 1.27 1.27)
					(thickness 0.15)
				)
				(justify left bottom)
				(hide yes)
			)
		)
		(property "Description" "SMD Multilayer Ceramic Capacitor, 0.1 µF, 50 V, 0402 [1005 Metric], ± 10%, X5R, GRM Series"
			(at 271.78 114.3 0)
			(effects
				(font
					(size 1.27 1.27)
				)
				(hide yes)
			)
		)
		(property "MPN" "GRM155R61H104KE14D"
			(at 289.56 93.98 0)
			(effects
				(font
					(size 1.27 1.27)
					(thickness 0.15)
				)
				(justify left bottom)
				(hide yes)
			)
		)
		(property "Manufacturer" "Murata"
			(at 292.1 93.98 0)
			(effects
				(font
					(size 1.27 1.27)
					(thickness 0.15)
				)
				(justify left bottom)
				(hide yes)
			)
		)
		(property "License" "Apache-2.0"
			(at 294.64 93.98 0)
			(effects
				(font
					(size 1.27 1.27)
					(thickness 0.15)
				)
				(justify left bottom)
				(hide yes)
			)
		)
		(property "Val" "100n"
			(at 268.605 113.0236 90)
			(effects
				(font
					(size 1.27 1.27)
					(thickness 0.15)
				)
				(justify left)
			)
		)
		(property "Voltage" "50V"
			(at 299.72 93.98 0)
			(effects
				(font
					(size 1.27 1.27)
				)
				(justify left bottom)
				(hide yes)
			)
		)
		(property "Dielectric" "X5R"
			(at 302.26 93.98 0)
			(effects
				(font
					(size 1.27 1.27)
				)
				(justify left bottom)
				(hide yes)
			)
		)
		(property "Author" "Antmicro"
			(at 297.18 93.98 0)
			(effects
				(font
					(size 1.27 1.27)
					(thickness 0.15)
				)
				(justify left bottom)
				(hide yes)
			)
		)
		(pin "1"
		)
		(pin "2"
		)
		(instances
			(project "thunderbolt-to-10gbe-adapter"
				(path ""
					(reference "C41")
					(unit 1)
				)
			)
		)
	)
	(symbol
		(lib_id "antmicropower:GND")
		(at 269.24 187.96 0)
		(unit 1)
		(exclude_from_sim no)
		(in_bom yes)
		(on_board yes)
		(dnp no)
		(property "Reference" "#PWR072"
			(at 269.24 194.31 0)
			(effects
				(font
					(size 1.27 1.27)
				)
				(hide yes)
			)
		)
		(property "Value" "GND"
			(at 269.24 191.77 0)
			(effects
				(font
					(size 1.27 1.27)
				)
			)
		)
		(property "Footprint" ""
			(at 269.24 187.96 0)
			(effects
				(font
					(size 1.27 1.27)
				)
				(hide yes)
			)
		)
		(property "Datasheet" ""
			(at 269.24 187.96 0)
			(effects
				(font
					(size 1.27 1.27)
				)
				(hide yes)
			)
		)
		(property "Description" ""
			(at 269.24 187.96 0)
			(effects
				(font
					(size 1.27 1.27)
				)
				(hide yes)
			)
		)
		(property "Author" "Antmicro"
			(at 278.13 195.58 0)
			(effects
				(font
					(size 1.27 1.27)
					(thickness 0.15)
				)
				(justify left bottom)
				(hide yes)
			)
		)
		(property "License" "Apache-2.0"
			(at 278.13 198.12 0)
			(effects
				(font
					(size 1.27 1.27)
					(thickness 0.15)
				)
				(justify left bottom)
				(hide yes)
			)
		)
		(pin "1"
		)
		(instances
			(project "thunderbolt-to-10gbe-adapter"
				(path ""
					(reference "#PWR072")
					(unit 1)
				)
			)
		)
	)
	(symbol
		(lib_id "antmicroResonators:Resonator_25MHz_ABM8G")
		(at 254 119.38 270)
		(unit 1)
		(exclude_from_sim no)
		(in_bom yes)
		(on_board yes)
		(dnp no)
		(fields_autoplaced yes)
		(property "Reference" "Y1"
			(at 257.81 121.92 90)
			(effects
				(font
					(size 1.27 1.27)
					(thickness 0.15)
				)
				(justify left)
			)
		)
		(property "Value" "Resonator_25MHz_ABM8G"
			(at 241.3 134.62 0)
			(effects
				(font
					(size 1.27 1.27)
					(thickness 0.15)
				)
				(justify left bottom)
				(hide yes)
			)
		)
		(property "Footprint" "antmicro-footprints:Resonator_SMD_Abracon_ABM8G_3.2x2.5mm"
			(at 238.76 134.62 0)
			(effects
				(font
					(size 1.27 1.27)
					(thickness 0.15)
				)
				(justify left bottom)
				(hide yes)
			)
		)
		(property "Datasheet" "https://abracon.com/Resonators/ABM8G.pdf"
			(at 236.22 134.62 0)
			(effects
				(font
					(size 1.27 1.27)
					(thickness 0.15)
				)
				(justify left bottom)
				(hide yes)
			)
		)
		(property "Description" "Crystal, 25 MHz, SMD, 3.2mm x 2.5mm, 30 ppm, 18 pF, 20 ppm, ABM8G"
			(at 254 119.38 0)
			(effects
				(font
					(size 1.27 1.27)
				)
				(hide yes)
			)
		)
		(property "MPN" "ABM8G-25.000MHZ-18-D2Y-T3"
			(at 257.81 123.19 90)
			(effects
				(font
					(size 1.27 1.27)
					(thickness 0.15)
				)
				(justify left)
				(hide yes)
			)
		)
		(property "Manufacturer" "Abracon"
			(at 233.68 134.62 0)
			(effects
				(font
					(size 1.27 1.27)
					(thickness 0.15)
				)
				(justify left bottom)
				(hide yes)
			)
		)
		(property "License" "Apache-2.0"
			(at 228.6 134.62 0)
			(effects
				(font
					(size 1.27 1.27)
					(thickness 0.15)
				)
				(justify left bottom)
				(hide yes)
			)
		)
		(property "Author" "Antmicro"
			(at 231.14 134.62 0)
			(effects
				(font
					(size 1.27 1.27)
					(thickness 0.15)
				)
				(justify left bottom)
				(hide yes)
			)
		)
		(property "Val" "25 MHz"
			(at 257.81 124.46 90)
			(effects
				(font
					(size 1.27 1.27)
					(thickness 0.15)
				)
				(justify left)
			)
		)
		(pin "1"
		)
		(pin "2"
		)
		(pin "3"
		)
		(pin "4"
		)
		(instances
			(project "thunderbolt-to-10gbe-adapter"
				(path ""
					(reference "Y1")
					(unit 1)
				)
			)
		)
	)
	(symbol
		(lib_id "antmicroCapacitors0402:C_220n_0402")
		(at 339.09 68.58 0)
		(unit 1)
		(exclude_from_sim no)
		(in_bom yes)
		(on_board yes)
		(dnp no)
		(property "Reference" "C47"
			(at 338.074 67.31 0)
			(effects
				(font
					(size 1.27 1.27)
					(thickness 0.15)
				)
			)
		)
		(property "Value" "C_220n_0402"
			(at 359.41 78.74 0)
			(effects
				(font
					(size 1.27 1.27)
					(thickness 0.15)
				)
				(justify left bottom)
				(hide yes)
			)
		)
		(property "Footprint" "antmicro-footprints:C_0402_1005Metric"
			(at 359.41 81.28 0)
			(effects
				(font
					(size 1.27 1.27)
					(thickness 0.15)
				)
				(justify left bottom)
				(hide yes)
			)
		)
		(property "Datasheet" "https://www.yageo.com/en/Chart/Download/pdf/CC0402KRX5R6BB224"
			(at 359.41 83.82 0)
			(effects
				(font
					(size 1.27 1.27)
					(thickness 0.15)
				)
				(justify left bottom)
				(hide yes)
			)
		)
		(property "Description" "SMD Multilayer Ceramic Capacitor, 0.22 µF, 10 V, 0402 [1005 Metric], ± 10%, X5R, CC Series"
			(at 339.09 68.58 0)
			(effects
				(font
					(size 1.27 1.27)
				)
				(hide yes)
			)
		)
		(property "MPN" "CC0402KRX5R6BB224"
			(at 359.41 86.36 0)
			(effects
				(font
					(size 1.27 1.27)
					(thickness 0.15)
				)
				(justify left bottom)
				(hide yes)
			)
		)
		(property "Manufacturer" "YAGEO"
			(at 359.41 88.9 0)
			(effects
				(font
					(size 1.27 1.27)
					(thickness 0.15)
				)
				(justify left bottom)
				(hide yes)
			)
		)
		(property "License" "Apache-2.0"
			(at 359.41 91.44 0)
			(effects
				(font
					(size 1.27 1.27)
					(thickness 0.15)
				)
				(justify left bottom)
				(hide yes)
			)
		)
		(property "Val" "220n"
			(at 345.186 67.31 0)
			(effects
				(font
					(size 1.27 1.27)
					(thickness 0.15)
				)
			)
		)
		(property "Voltage" ""
			(at 359.41 96.52 0)
			(effects
				(font
					(size 1.27 1.27)
				)
				(justify left bottom)
				(hide yes)
			)
		)
		(property "Dielectric" ""
			(at 359.41 99.06 0)
			(effects
				(font
					(size 1.27 1.27)
				)
				(justify left bottom)
				(hide yes)
			)
		)
		(property "Author" "Antmicro"
			(at 359.41 93.98 0)
			(effects
				(font
					(size 1.27 1.27)
					(thickness 0.15)
				)
				(justify left bottom)
				(hide yes)
			)
		)
		(pin "1"
		)
		(pin "2"
		)
		(instances
			(project "thunderbolt-to-10gbe-adapter"
				(path ""
					(reference "C47")
					(unit 1)
				)
			)
		)
	)
	(symbol
		(lib_id "antmicropower:GND")
		(at 196.85 102.87 0)
		(unit 1)
		(exclude_from_sim no)
		(in_bom yes)
		(on_board yes)
		(dnp no)
		(property "Reference" "#PWR068"
			(at 196.85 109.22 0)
			(effects
				(font
					(size 1.27 1.27)
				)
				(hide yes)
			)
		)
		(property "Value" "GND"
			(at 196.85 106.68 0)
			(effects
				(font
					(size 1.27 1.27)
				)
			)
		)
		(property "Footprint" ""
			(at 196.85 102.87 0)
			(effects
				(font
					(size 1.27 1.27)
				)
				(hide yes)
			)
		)
		(property "Datasheet" ""
			(at 196.85 102.87 0)
			(effects
				(font
					(size 1.27 1.27)
				)
				(hide yes)
			)
		)
		(property "Description" ""
			(at 196.85 102.87 0)
			(effects
				(font
					(size 1.27 1.27)
				)
				(hide yes)
			)
		)
		(property "Author" "Antmicro"
			(at 205.74 110.49 0)
			(effects
				(font
					(size 1.27 1.27)
					(thickness 0.15)
				)
				(justify left bottom)
				(hide yes)
			)
		)
		(property "License" "Apache-2.0"
			(at 205.74 113.03 0)
			(effects
				(font
					(size 1.27 1.27)
					(thickness 0.15)
				)
				(justify left bottom)
				(hide yes)
			)
		)
		(pin "1"
		)
		(instances
			(project "thunderbolt-to-10gbe-adapter"
				(path ""
					(reference "#PWR068")
					(unit 1)
				)
			)
		)
	)
	(symbol
		(lib_id "antmicroResistors0402:R_10k_0402")
		(at 101.6 246.38 0)
		(unit 1)
		(exclude_from_sim no)
		(in_bom yes)
		(on_board yes)
		(dnp no)
		(property "Reference" "R49"
			(at 100.33 245.11 0)
			(effects
				(font
					(size 1.27 1.27)
					(thickness 0.15)
				)
			)
		)
		(property "Value" "R_10k_0402"
			(at 121.92 259.08 0)
			(effects
				(font
					(size 1.27 1.27)
					(thickness 0.15)
				)
				(justify left bottom)
				(hide yes)
			)
		)
		(property "Footprint" "antmicro-footprints:R_0402_1005Metric"
			(at 121.92 261.62 0)
			(effects
				(font
					(size 1.27 1.27)
					(thickness 0.15)
				)
				(justify left bottom)
				(hide yes)
			)
		)
		(property "Datasheet" "https://www.bourns.com/docs/product-datasheets/cr.pdf"
			(at 121.92 264.16 0)
			(effects
				(font
					(size 1.27 1.27)
					(thickness 0.15)
				)
				(justify left bottom)
				(hide yes)
			)
		)
		(property "Description" "SMD Chip Resistor, 10 kohm, ± 1%, 62.5 mW, 0402 [1005 Metric], Thick Film, General Purpose"
			(at 101.6 246.38 0)
			(effects
				(font
					(size 1.27 1.27)
				)
				(hide yes)
			)
		)
		(property "MPN" "CR0402-FX-1002GLF"
			(at 121.92 266.7 0)
			(effects
				(font
					(size 1.27 1.27)
					(thickness 0.15)
				)
				(justify left bottom)
				(hide yes)
			)
		)
		(property "Manufacturer" "Bourns"
			(at 121.92 269.24 0)
			(effects
				(font
					(size 1.27 1.27)
					(thickness 0.15)
				)
				(justify left bottom)
				(hide yes)
			)
		)
		(property "License" "Apache-2.0"
			(at 121.92 271.78 0)
			(effects
				(font
					(size 1.27 1.27)
					(thickness 0.15)
				)
				(justify left bottom)
				(hide yes)
			)
		)
		(property "Val" "10k"
			(at 107.95 245.11 0)
			(effects
				(font
					(size 1.27 1.27)
					(thickness 0.15)
				)
			)
		)
		(property "Tolerance" "1%"
			(at 121.92 256.54 0)
			(effects
				(font
					(size 1.27 1.27)
				)
				(justify left bottom)
				(hide yes)
			)
		)
		(property "Author" "Antmicro"
			(at 121.92 274.32 0)
			(effects
				(font
					(size 1.27 1.27)
					(thickness 0.15)
				)
				(justify left bottom)
				(hide yes)
			)
		)
		(pin "1"
		)
		(pin "2"
		)
		(instances
			(project "thunderbolt-to-10gbe-adapter"
				(path ""
					(reference "R49")
					(unit 1)
				)
			)
		)
	)
	(symbol
		(lib_id "antmicroResistors0402:R_1M_0402")
		(at 106.68 102.87 90)
		(unit 1)
		(exclude_from_sim no)
		(in_bom yes)
		(on_board yes)
		(dnp no)
		(fields_autoplaced yes)
		(property "Reference" "R55"
			(at 108.585 99.06 90)
			(effects
				(font
					(size 1.27 1.27)
					(thickness 0.15)
				)
				(justify right)
			)
		)
		(property "Value" "R_1M_0402"
			(at 119.38 82.55 0)
			(effects
				(font
					(size 1.27 1.27)
					(thickness 0.15)
				)
				(justify left bottom)
				(hide yes)
			)
		)
		(property "Footprint" "antmicro-footprints:R_0402_1005Metric"
			(at 121.92 82.55 0)
			(effects
				(font
					(size 1.27 1.27)
					(thickness 0.15)
				)
				(justify left bottom)
				(hide yes)
			)
		)
		(property "Datasheet" "https://www.bourns.com/docs/product-datasheets/cr.pdf"
			(at 124.46 82.55 0)
			(effects
				(font
					(size 1.27 1.27)
					(thickness 0.15)
				)
				(justify left bottom)
				(hide yes)
			)
		)
		(property "Description" "SMD Chip Resistor, 1 Mohm, ± 1%, 62.5 mW, 0402 [1005 Metric], Thick Film, General Purpose"
			(at 106.68 102.87 0)
			(effects
				(font
					(size 1.27 1.27)
				)
				(hide yes)
			)
		)
		(property "MPN" "CR0402-FX-1004GLF"
			(at 127 82.55 0)
			(effects
				(font
					(size 1.27 1.27)
					(thickness 0.15)
				)
				(justify left bottom)
				(hide yes)
			)
		)
		(property "Manufacturer" "Bourns"
			(at 129.54 82.55 0)
			(effects
				(font
					(size 1.27 1.27)
					(thickness 0.15)
				)
				(justify left bottom)
				(hide yes)
			)
		)
		(property "License" "Apache-2.0"
			(at 132.08 82.55 0)
			(effects
				(font
					(size 1.27 1.27)
					(thickness 0.15)
				)
				(justify left bottom)
				(hide yes)
			)
		)
		(property "Val" "1M"
			(at 108.585 101.6 90)
			(effects
				(font
					(size 1.27 1.27)
					(thickness 0.15)
				)
				(justify right)
			)
		)
		(property "Tolerance" "1%"
			(at 116.84 82.55 0)
			(effects
				(font
					(size 1.27 1.27)
				)
				(justify left bottom)
				(hide yes)
			)
		)
		(property "Author" "Antmicro"
			(at 134.62 82.55 0)
			(effects
				(font
					(size 1.27 1.27)
					(thickness 0.15)
				)
				(justify left bottom)
				(hide yes)
			)
		)
		(pin "1"
		)
		(pin "2"
		)
		(instances
			(project "thunderbolt-to-10gbe-adapter"
				(path ""
					(reference "R55")
					(unit 1)
				)
			)
		)
	)
	(symbol
		(lib_id "antmicroResistors0402:R_100k_0402")
		(at 33.02 203.2 0)
		(unit 1)
		(exclude_from_sim no)
		(in_bom yes)
		(on_board yes)
		(dnp no)
		(fields_autoplaced yes)
		(property "Reference" "R34"
			(at 35.56 196.85 0)
			(effects
				(font
					(size 1.27 1.27)
					(thickness 0.15)
				)
			)
		)
		(property "Value" "R_100k_0402"
			(at 53.34 215.9 0)
			(effects
				(font
					(size 1.27 1.27)
					(thickness 0.15)
				)
				(justify left bottom)
				(hide yes)
			)
		)
		(property "Footprint" "antmicro-footprints:R_0402_1005Metric"
			(at 53.34 218.44 0)
			(effects
				(font
					(size 1.27 1.27)
					(thickness 0.15)
				)
				(justify left bottom)
				(hide yes)
			)
		)
		(property "Datasheet" "https://www.bourns.com/docs/product-datasheets/cr.pdf"
			(at 53.34 220.98 0)
			(effects
				(font
					(size 1.27 1.27)
					(thickness 0.15)
				)
				(justify left bottom)
				(hide yes)
			)
		)
		(property "Description" "SMD Chip Resistor, 100 kohm, ± 1%, 62.5 mW, 0402 [1005 Metric], Thick Film, General Purpose"
			(at 33.02 203.2 0)
			(effects
				(font
					(size 1.27 1.27)
				)
				(hide yes)
			)
		)
		(property "MPN" "CR0402-FX-1003GLF"
			(at 53.34 223.52 0)
			(effects
				(font
					(size 1.27 1.27)
					(thickness 0.15)
				)
				(justify left bottom)
				(hide yes)
			)
		)
		(property "Manufacturer" "Bourns"
			(at 53.34 226.06 0)
			(effects
				(font
					(size 1.27 1.27)
					(thickness 0.15)
				)
				(justify left bottom)
				(hide yes)
			)
		)
		(property "License" "Apache-2.0"
			(at 53.34 228.6 0)
			(effects
				(font
					(size 1.27 1.27)
					(thickness 0.15)
				)
				(justify left bottom)
				(hide yes)
			)
		)
		(property "Val" "100k"
			(at 35.56 199.39 0)
			(effects
				(font
					(size 1.27 1.27)
					(thickness 0.15)
				)
			)
		)
		(property "Tolerance" "1%"
			(at 53.34 213.36 0)
			(effects
				(font
					(size 1.27 1.27)
				)
				(justify left bottom)
				(hide yes)
			)
		)
		(property "Author" "Antmicro"
			(at 53.34 231.14 0)
			(effects
				(font
					(size 1.27 1.27)
					(thickness 0.15)
				)
				(justify left bottom)
				(hide yes)
			)
		)
		(pin "1"
		)
		(pin "2"
		)
		(instances
			(project "thunderbolt-to-10gbe-adapter"
				(path ""
					(reference "R34")
					(unit 1)
				)
			)
		)
	)
	(symbol
		(lib_id "antmicroCapacitors0402:C_220n_0402")
		(at 341.63 63.5 0)
		(unit 1)
		(exclude_from_sim no)
		(in_bom yes)
		(on_board yes)
		(dnp no)
		(property "Reference" "C50"
			(at 340.614 64.77 0)
			(effects
				(font
					(size 1.27 1.27)
					(thickness 0.15)
				)
			)
		)
		(property "Value" "C_220n_0402"
			(at 361.95 73.66 0)
			(effects
				(font
					(size 1.27 1.27)
					(thickness 0.15)
				)
				(justify left bottom)
				(hide yes)
			)
		)
		(property "Footprint" "antmicro-footprints:C_0402_1005Metric"
			(at 361.95 76.2 0)
			(effects
				(font
					(size 1.27 1.27)
					(thickness 0.15)
				)
				(justify left bottom)
				(hide yes)
			)
		)
		(property "Datasheet" "https://www.yageo.com/en/Chart/Download/pdf/CC0402KRX5R6BB224"
			(at 361.95 78.74 0)
			(effects
				(font
					(size 1.27 1.27)
					(thickness 0.15)
				)
				(justify left bottom)
				(hide yes)
			)
		)
		(property "Description" "SMD Multilayer Ceramic Capacitor, 0.22 µF, 10 V, 0402 [1005 Metric], ± 10%, X5R, CC Series"
			(at 341.63 63.5 0)
			(effects
				(font
					(size 1.27 1.27)
				)
				(hide yes)
			)
		)
		(property "MPN" "CC0402KRX5R6BB224"
			(at 361.95 81.28 0)
			(effects
				(font
					(size 1.27 1.27)
					(thickness 0.15)
				)
				(justify left bottom)
				(hide yes)
			)
		)
		(property "Manufacturer" "YAGEO"
			(at 361.95 83.82 0)
			(effects
				(font
					(size 1.27 1.27)
					(thickness 0.15)
				)
				(justify left bottom)
				(hide yes)
			)
		)
		(property "License" "Apache-2.0"
			(at 361.95 86.36 0)
			(effects
				(font
					(size 1.27 1.27)
					(thickness 0.15)
				)
				(justify left bottom)
				(hide yes)
			)
		)
		(property "Val" "220n"
			(at 347.726 64.77 0)
			(effects
				(font
					(size 1.27 1.27)
					(thickness 0.15)
				)
			)
		)
		(property "Voltage" ""
			(at 361.95 91.44 0)
			(effects
				(font
					(size 1.27 1.27)
				)
				(justify left bottom)
				(hide yes)
			)
		)
		(property "Dielectric" ""
			(at 361.95 93.98 0)
			(effects
				(font
					(size 1.27 1.27)
				)
				(justify left bottom)
				(hide yes)
			)
		)
		(property "Author" "Antmicro"
			(at 361.95 88.9 0)
			(effects
				(font
					(size 1.27 1.27)
					(thickness 0.15)
				)
				(justify left bottom)
				(hide yes)
			)
		)
		(pin "1"
		)
		(pin "2"
		)
		(instances
			(project "thunderbolt-to-10gbe-adapter"
				(path ""
					(reference "C50")
					(unit 1)
				)
			)
		)
	)
	(symbol
		(lib_id "antmicroResistors0402:R_10k_0402")
		(at 189.23 191.77 0)
		(unit 1)
		(exclude_from_sim no)
		(in_bom yes)
		(on_board yes)
		(dnp no)
		(property "Reference" "R65"
			(at 195.58 190.5 0)
			(effects
				(font
					(size 1.27 1.27)
					(thickness 0.15)
				)
			)
		)
		(property "Value" "R_10k_0402"
			(at 209.55 204.47 0)
			(effects
				(font
					(size 1.27 1.27)
					(thickness 0.15)
				)
				(justify left bottom)
				(hide yes)
			)
		)
		(property "Footprint" "antmicro-footprints:R_0402_1005Metric"
			(at 209.55 207.01 0)
			(effects
				(font
					(size 1.27 1.27)
					(thickness 0.15)
				)
				(justify left bottom)
				(hide yes)
			)
		)
		(property "Datasheet" "https://www.bourns.com/docs/product-datasheets/cr.pdf"
			(at 209.55 209.55 0)
			(effects
				(font
					(size 1.27 1.27)
					(thickness 0.15)
				)
				(justify left bottom)
				(hide yes)
			)
		)
		(property "Description" "SMD Chip Resistor, 10 kohm, ± 1%, 62.5 mW, 0402 [1005 Metric], Thick Film, General Purpose"
			(at 189.23 191.77 0)
			(effects
				(font
					(size 1.27 1.27)
				)
				(hide yes)
			)
		)
		(property "MPN" "CR0402-FX-1002GLF"
			(at 209.55 212.09 0)
			(effects
				(font
					(size 1.27 1.27)
					(thickness 0.15)
				)
				(justify left bottom)
				(hide yes)
			)
		)
		(property "Manufacturer" "Bourns"
			(at 209.55 214.63 0)
			(effects
				(font
					(size 1.27 1.27)
					(thickness 0.15)
				)
				(justify left bottom)
				(hide yes)
			)
		)
		(property "License" "Apache-2.0"
			(at 209.55 217.17 0)
			(effects
				(font
					(size 1.27 1.27)
					(thickness 0.15)
				)
				(justify left bottom)
				(hide yes)
			)
		)
		(property "Val" "10k"
			(at 187.96 190.5 0)
			(effects
				(font
					(size 1.27 1.27)
					(thickness 0.15)
				)
			)
		)
		(property "Tolerance" "1%"
			(at 209.55 201.93 0)
			(effects
				(font
					(size 1.27 1.27)
				)
				(justify left bottom)
				(hide yes)
			)
		)
		(property "Author" "Antmicro"
			(at 209.55 219.71 0)
			(effects
				(font
					(size 1.27 1.27)
					(thickness 0.15)
				)
				(justify left bottom)
				(hide yes)
			)
		)
		(pin "1"
		)
		(pin "2"
		)
		(instances
			(project "thunderbolt-to-10gbe-adapter"
				(path ""
					(reference "R65")
					(unit 1)
				)
			)
		)
	)
	(symbol
		(lib_id "antmicropower:GND")
		(at 30.48 270.51 0)
		(mirror y)
		(unit 1)
		(exclude_from_sim no)
		(in_bom yes)
		(on_board yes)
		(dnp no)
		(property "Reference" "#PWR059"
			(at 30.48 276.86 0)
			(effects
				(font
					(size 1.27 1.27)
				)
				(hide yes)
			)
		)
		(property "Value" "GND"
			(at 30.48 274.32 0)
			(effects
				(font
					(size 1.27 1.27)
				)
			)
		)
		(property "Footprint" ""
			(at 30.48 270.51 0)
			(effects
				(font
					(size 1.27 1.27)
				)
				(hide yes)
			)
		)
		(property "Datasheet" ""
			(at 30.48 270.51 0)
			(effects
				(font
					(size 1.27 1.27)
				)
				(hide yes)
			)
		)
		(property "Description" ""
			(at 30.48 270.51 0)
			(effects
				(font
					(size 1.27 1.27)
				)
				(hide yes)
			)
		)
		(property "Author" "Antmicro"
			(at 21.59 278.13 0)
			(effects
				(font
					(size 1.27 1.27)
					(thickness 0.15)
				)
				(justify left bottom)
				(hide yes)
			)
		)
		(property "License" "Apache-2.0"
			(at 21.59 280.67 0)
			(effects
				(font
					(size 1.27 1.27)
					(thickness 0.15)
				)
				(justify left bottom)
				(hide yes)
			)
		)
		(pin "1"
		)
		(instances
			(project "thunderbolt-to-10gbe-adapter"
				(path ""
					(reference "#PWR059")
					(unit 1)
				)
			)
		)
	)
	(symbol
		(lib_id "antmicropower:GND")
		(at 106.68 105.41 0)
		(unit 1)
		(exclude_from_sim no)
		(in_bom yes)
		(on_board yes)
		(dnp no)
		(property "Reference" "#PWR061"
			(at 106.68 111.76 0)
			(effects
				(font
					(size 1.27 1.27)
				)
				(hide yes)
			)
		)
		(property "Value" "GND"
			(at 106.68 109.22 0)
			(effects
				(font
					(size 1.27 1.27)
				)
			)
		)
		(property "Footprint" ""
			(at 106.68 105.41 0)
			(effects
				(font
					(size 1.27 1.27)
				)
				(hide yes)
			)
		)
		(property "Datasheet" ""
			(at 106.68 105.41 0)
			(effects
				(font
					(size 1.27 1.27)
				)
				(hide yes)
			)
		)
		(property "Description" ""
			(at 106.68 105.41 0)
			(effects
				(font
					(size 1.27 1.27)
				)
				(hide yes)
			)
		)
		(property "Author" "Antmicro"
			(at 115.57 113.03 0)
			(effects
				(font
					(size 1.27 1.27)
					(thickness 0.15)
				)
				(justify left bottom)
				(hide yes)
			)
		)
		(property "License" "Apache-2.0"
			(at 115.57 115.57 0)
			(effects
				(font
					(size 1.27 1.27)
					(thickness 0.15)
				)
				(justify left bottom)
				(hide yes)
			)
		)
		(pin "1"
		)
		(instances
			(project "thunderbolt-to-10gbe-adapter"
				(path ""
					(reference "#PWR061")
					(unit 1)
				)
			)
		)
	)
	(symbol
		(lib_id "antmicroCapacitors0402:C_220n_0402")
		(at 339.09 45.72 0)
		(unit 1)
		(exclude_from_sim no)
		(in_bom yes)
		(on_board yes)
		(dnp no)
		(property "Reference" "C44"
			(at 338.074 44.704 0)
			(effects
				(font
					(size 1.27 1.27)
					(thickness 0.15)
				)
			)
		)
		(property "Value" "C_220n_0402"
			(at 359.41 55.88 0)
			(effects
				(font
					(size 1.27 1.27)
					(thickness 0.15)
				)
				(justify left bottom)
				(hide yes)
			)
		)
		(property "Footprint" "antmicro-footprints:C_0402_1005Metric"
			(at 359.41 58.42 0)
			(effects
				(font
					(size 1.27 1.27)
					(thickness 0.15)
				)
				(justify left bottom)
				(hide yes)
			)
		)
		(property "Datasheet" "https://www.yageo.com/en/Chart/Download/pdf/CC0402KRX5R6BB224"
			(at 359.41 60.96 0)
			(effects
				(font
					(size 1.27 1.27)
					(thickness 0.15)
				)
				(justify left bottom)
				(hide yes)
			)
		)
		(property "Description" "SMD Multilayer Ceramic Capacitor, 0.22 µF, 10 V, 0402 [1005 Metric], ± 10%, X5R, CC Series"
			(at 339.09 45.72 0)
			(effects
				(font
					(size 1.27 1.27)
				)
				(hide yes)
			)
		)
		(property "MPN" "CC0402KRX5R6BB224"
			(at 359.41 63.5 0)
			(effects
				(font
					(size 1.27 1.27)
					(thickness 0.15)
				)
				(justify left bottom)
				(hide yes)
			)
		)
		(property "Manufacturer" "YAGEO"
			(at 359.41 66.04 0)
			(effects
				(font
					(size 1.27 1.27)
					(thickness 0.15)
				)
				(justify left bottom)
				(hide yes)
			)
		)
		(property "License" "Apache-2.0"
			(at 359.41 68.58 0)
			(effects
				(font
					(size 1.27 1.27)
					(thickness 0.15)
				)
				(justify left bottom)
				(hide yes)
			)
		)
		(property "Val" "220n"
			(at 344.932 44.704 0)
			(effects
				(font
					(size 1.27 1.27)
					(thickness 0.15)
				)
			)
		)
		(property "Voltage" ""
			(at 359.41 73.66 0)
			(effects
				(font
					(size 1.27 1.27)
				)
				(justify left bottom)
				(hide yes)
			)
		)
		(property "Dielectric" ""
			(at 359.41 76.2 0)
			(effects
				(font
					(size 1.27 1.27)
				)
				(justify left bottom)
				(hide yes)
			)
		)
		(property "Author" "Antmicro"
			(at 359.41 71.12 0)
			(effects
				(font
					(size 1.27 1.27)
					(thickness 0.15)
				)
				(justify left bottom)
				(hide yes)
			)
		)
		(pin "1"
		)
		(pin "2"
		)
		(instances
			(project "thunderbolt-to-10gbe-adapter"
				(path ""
					(reference "C44")
					(unit 1)
				)
			)
		)
	)
	(symbol
		(lib_id "antmicroResistors0402:R_100k_0402")
		(at 101.6 248.92 0)
		(unit 1)
		(exclude_from_sim no)
		(in_bom yes)
		(on_board yes)
		(dnp no)
		(property "Reference" "R50"
			(at 100.33 247.65 0)
			(effects
				(font
					(size 1.27 1.27)
					(thickness 0.15)
				)
			)
		)
		(property "Value" "R_100k_0402"
			(at 121.92 261.62 0)
			(effects
				(font
					(size 1.27 1.27)
					(thickness 0.15)
				)
				(justify left bottom)
				(hide yes)
			)
		)
		(property "Footprint" "antmicro-footprints:R_0402_1005Metric"
			(at 121.92 264.16 0)
			(effects
				(font
					(size 1.27 1.27)
					(thickness 0.15)
				)
				(justify left bottom)
				(hide yes)
			)
		)
		(property "Datasheet" "https://www.bourns.com/docs/product-datasheets/cr.pdf"
			(at 121.92 266.7 0)
			(effects
				(font
					(size 1.27 1.27)
					(thickness 0.15)
				)
				(justify left bottom)
				(hide yes)
			)
		)
		(property "Description" "SMD Chip Resistor, 100 kohm, ± 1%, 62.5 mW, 0402 [1005 Metric], Thick Film, General Purpose"
			(at 101.6 248.92 0)
			(effects
				(font
					(size 1.27 1.27)
				)
				(hide yes)
			)
		)
		(property "MPN" "CR0402-FX-1003GLF"
			(at 121.92 269.24 0)
			(effects
				(font
					(size 1.27 1.27)
					(thickness 0.15)
				)
				(justify left bottom)
				(hide yes)
			)
		)
		(property "Manufacturer" "Bourns"
			(at 121.92 271.78 0)
			(effects
				(font
					(size 1.27 1.27)
					(thickness 0.15)
				)
				(justify left bottom)
				(hide yes)
			)
		)
		(property "License" "Apache-2.0"
			(at 121.92 274.32 0)
			(effects
				(font
					(size 1.27 1.27)
					(thickness 0.15)
				)
				(justify left bottom)
				(hide yes)
			)
		)
		(property "Val" "100k"
			(at 108.585 247.65 0)
			(effects
				(font
					(size 1.27 1.27)
					(thickness 0.15)
				)
			)
		)
		(property "Tolerance" "1%"
			(at 121.92 259.08 0)
			(effects
				(font
					(size 1.27 1.27)
				)
				(justify left bottom)
				(hide yes)
			)
		)
		(property "Author" "Antmicro"
			(at 121.92 276.86 0)
			(effects
				(font
					(size 1.27 1.27)
					(thickness 0.15)
				)
				(justify left bottom)
				(hide yes)
			)
		)
		(pin "1"
		)
		(pin "2"
		)
		(instances
			(project "thunderbolt-to-10gbe-adapter"
				(path ""
					(reference "R50")
					(unit 1)
				)
			)
		)
	)
	(symbol
		(lib_id "antmicroClockTimingClockGeneratorsPLLsFrequencySynthesizers:SI52112-B6-GT")
		(at 278.13 119.38 0)
		(unit 1)
		(exclude_from_sim no)
		(in_bom yes)
		(on_board yes)
		(dnp no)
		(fields_autoplaced yes)
		(property "Reference" "U5"
			(at 290.195 111.76 0)
			(effects
				(font
					(size 1.27 1.27)
					(thickness 0.15)
				)
			)
		)
		(property "Value" "SI52112-B6-GT"
			(at 316.23 124.46 0)
			(effects
				(font
					(size 1.27 1.27)
					(thickness 0.15)
				)
				(justify left bottom)
				(hide yes)
			)
		)
		(property "Footprint" "antmicro-footprints:TSSOP-8_3x4.4mm_P0.65mm"
			(at 316.23 127 0)
			(effects
				(font
					(size 1.27 1.27)
					(thickness 0.15)
				)
				(justify left bottom)
				(hide yes)
			)
		)
		(property "Datasheet" "https://www.skyworksinc.com/-/media/Skyworks/SL/documents/public/data-sheets/Si52112-B5-B6.pdf"
			(at 316.23 129.54 0)
			(effects
				(font
					(size 1.27 1.27)
					(thickness 0.15)
				)
				(justify left bottom)
				(hide yes)
			)
		)
		(property "Description" "Clock Generator, 100MHz, 2.97V to 3.63V, 2 Outputs, TSSOP-8"
			(at 278.13 119.38 0)
			(effects
				(font
					(size 1.27 1.27)
				)
				(hide yes)
			)
		)
		(property "MPN" "SI52112-B6-GT"
			(at 290.195 114.3 0)
			(effects
				(font
					(size 1.27 1.27)
					(thickness 0.15)
				)
			)
		)
		(property "Manufacturer" "Skyworks Solutions"
			(at 316.23 134.62 0)
			(effects
				(font
					(size 1.27 1.27)
					(thickness 0.15)
				)
				(justify left bottom)
				(hide yes)
			)
		)
		(property "License" "Apache-2.0"
			(at 316.23 139.7 0)
			(effects
				(font
					(size 1.27 1.27)
					(thickness 0.15)
				)
				(justify left bottom)
				(hide yes)
			)
		)
		(property "Author" "Antmicro"
			(at 316.23 137.16 0)
			(effects
				(font
					(size 1.27 1.27)
					(thickness 0.15)
				)
				(justify left bottom)
				(hide yes)
			)
		)
		(pin "1"
		)
		(pin "2"
		)
		(pin "3"
		)
		(pin "4"
		)
		(pin "5"
		)
		(pin "6"
		)
		(pin "7"
		)
		(pin "8"
		)
		(instances
			(project "thunderbolt-to-10gbe-adapter"
				(path ""
					(reference "U5")
					(unit 1)
				)
			)
		)
	)
	(symbol
		(lib_id "antmicropower:GND")
		(at 309.88 199.39 0)
		(unit 1)
		(exclude_from_sim no)
		(in_bom yes)
		(on_board yes)
		(dnp no)
		(property "Reference" "#PWR075"
			(at 309.88 205.74 0)
			(effects
				(font
					(size 1.27 1.27)
				)
				(hide yes)
			)
		)
		(property "Value" "GND"
			(at 309.88 203.2 0)
			(effects
				(font
					(size 1.27 1.27)
				)
			)
		)
		(property "Footprint" ""
			(at 309.88 199.39 0)
			(effects
				(font
					(size 1.27 1.27)
				)
				(hide yes)
			)
		)
		(property "Datasheet" ""
			(at 309.88 199.39 0)
			(effects
				(font
					(size 1.27 1.27)
				)
				(hide yes)
			)
		)
		(property "Description" ""
			(at 309.88 199.39 0)
			(effects
				(font
					(size 1.27 1.27)
				)
				(hide yes)
			)
		)
		(property "Author" "Antmicro"
			(at 318.77 207.01 0)
			(effects
				(font
					(size 1.27 1.27)
					(thickness 0.15)
				)
				(justify left bottom)
				(hide yes)
			)
		)
		(property "License" "Apache-2.0"
			(at 318.77 209.55 0)
			(effects
				(font
					(size 1.27 1.27)
					(thickness 0.15)
				)
				(justify left bottom)
				(hide yes)
			)
		)
		(pin "1"
		)
		(instances
			(project "thunderbolt-to-10gbe-adapter"
				(path ""
					(reference "#PWR075")
					(unit 1)
				)
			)
		)
	)
	(symbol
		(lib_id "antmicroResistors0402:R_10k_0402")
		(at 189.23 189.23 0)
		(unit 1)
		(exclude_from_sim no)
		(in_bom yes)
		(on_board yes)
		(dnp no)
		(property "Reference" "R64"
			(at 195.58 187.96 0)
			(effects
				(font
					(size 1.27 1.27)
					(thickness 0.15)
				)
			)
		)
		(property "Value" "R_10k_0402"
			(at 209.55 201.93 0)
			(effects
				(font
					(size 1.27 1.27)
					(thickness 0.15)
				)
				(justify left bottom)
				(hide yes)
			)
		)
		(property "Footprint" "antmicro-footprints:R_0402_1005Metric"
			(at 209.55 204.47 0)
			(effects
				(font
					(size 1.27 1.27)
					(thickness 0.15)
				)
				(justify left bottom)
				(hide yes)
			)
		)
		(property "Datasheet" "https://www.bourns.com/docs/product-datasheets/cr.pdf"
			(at 209.55 207.01 0)
			(effects
				(font
					(size 1.27 1.27)
					(thickness 0.15)
				)
				(justify left bottom)
				(hide yes)
			)
		)
		(property "Description" "SMD Chip Resistor, 10 kohm, ± 1%, 62.5 mW, 0402 [1005 Metric], Thick Film, General Purpose"
			(at 189.23 189.23 0)
			(effects
				(font
					(size 1.27 1.27)
				)
				(hide yes)
			)
		)
		(property "MPN" "CR0402-FX-1002GLF"
			(at 209.55 209.55 0)
			(effects
				(font
					(size 1.27 1.27)
					(thickness 0.15)
				)
				(justify left bottom)
				(hide yes)
			)
		)
		(property "Manufacturer" "Bourns"
			(at 209.55 212.09 0)
			(effects
				(font
					(size 1.27 1.27)
					(thickness 0.15)
				)
				(justify left bottom)
				(hide yes)
			)
		)
		(property "License" "Apache-2.0"
			(at 209.55 214.63 0)
			(effects
				(font
					(size 1.27 1.27)
					(thickness 0.15)
				)
				(justify left bottom)
				(hide yes)
			)
		)
		(property "Val" "10k"
			(at 187.96 187.96 0)
			(effects
				(font
					(size 1.27 1.27)
					(thickness 0.15)
				)
			)
		)
		(property "Tolerance" "1%"
			(at 209.55 199.39 0)
			(effects
				(font
					(size 1.27 1.27)
				)
				(justify left bottom)
				(hide yes)
			)
		)
		(property "Author" "Antmicro"
			(at 209.55 217.17 0)
			(effects
				(font
					(size 1.27 1.27)
					(thickness 0.15)
				)
				(justify left bottom)
				(hide yes)
			)
		)
		(pin "1"
		)
		(pin "2"
		)
		(instances
			(project "thunderbolt-to-10gbe-adapter"
				(path ""
					(reference "R64")
					(unit 1)
				)
			)
		)
	)
	(symbol
		(lib_id "antmicropower:+3V3")
		(at 261.62 106.68 0)
		(unit 1)
		(exclude_from_sim no)
		(in_bom yes)
		(on_board yes)
		(dnp no)
		(property "Reference" "#PWR071"
			(at 276.86 106.68 0)
			(effects
				(font
					(size 1.27 1.27)
					(thickness 0.15)
				)
				(justify left bottom)
				(hide yes)
			)
		)
		(property "Value" "+3V3_TB"
			(at 261.62 102.87 0)
			(effects
				(font
					(size 1.27 1.27)
					(thickness 0.15)
				)
			)
		)
		(property "Footprint" ""
			(at 276.86 114.3 0)
			(effects
				(font
					(size 1.27 1.27)
					(thickness 0.15)
				)
				(justify left bottom)
				(hide yes)
			)
		)
		(property "Datasheet" ""
			(at 276.86 116.84 0)
			(effects
				(font
					(size 1.27 1.27)
					(thickness 0.15)
				)
				(justify left bottom)
				(hide yes)
			)
		)
		(property "Description" ""
			(at 276.86 119.38 0)
			(effects
				(font
					(size 1.27 1.27)
				)
				(justify left bottom)
				(hide yes)
			)
		)
		(property "Author" "Antmicro"
			(at 276.86 109.22 0)
			(effects
				(font
					(size 1.27 1.27)
					(thickness 0.15)
				)
				(justify left bottom)
				(hide yes)
			)
		)
		(property "License" "Apache-2.0"
			(at 276.86 111.76 0)
			(effects
				(font
					(size 1.27 1.27)
					(thickness 0.15)
				)
				(justify left bottom)
				(hide yes)
			)
		)
		(pin "1"
		)
		(instances
			(project "thunderbolt-to-10gbe-adapter"
				(path ""
					(reference "#PWR071")
					(unit 1)
				)
			)
		)
	)
	(symbol
		(lib_id "antmicropower:GND")
		(at 330.2 85.09 0)
		(unit 1)
		(exclude_from_sim no)
		(in_bom yes)
		(on_board yes)
		(dnp no)
		(property "Reference" "#PWR076"
			(at 330.2 91.44 0)
			(effects
				(font
					(size 1.27 1.27)
				)
				(hide yes)
			)
		)
		(property "Value" "GND"
			(at 330.2 88.9 0)
			(effects
				(font
					(size 1.27 1.27)
				)
			)
		)
		(property "Footprint" ""
			(at 330.2 85.09 0)
			(effects
				(font
					(size 1.27 1.27)
				)
				(hide yes)
			)
		)
		(property "Datasheet" ""
			(at 330.2 85.09 0)
			(effects
				(font
					(size 1.27 1.27)
				)
				(hide yes)
			)
		)
		(property "Description" ""
			(at 330.2 85.09 0)
			(effects
				(font
					(size 1.27 1.27)
				)
				(hide yes)
			)
		)
		(property "Author" "Antmicro"
			(at 339.09 92.71 0)
			(effects
				(font
					(size 1.27 1.27)
					(thickness 0.15)
				)
				(justify left bottom)
				(hide yes)
			)
		)
		(property "License" "Apache-2.0"
			(at 339.09 95.25 0)
			(effects
				(font
					(size 1.27 1.27)
					(thickness 0.15)
				)
				(justify left bottom)
				(hide yes)
			)
		)
		(pin "1"
		)
		(instances
			(project "thunderbolt-to-10gbe-adapter"
				(path ""
					(reference "#PWR076")
					(unit 1)
				)
			)
		)
	)
	(symbol
		(lib_id "antmicroCapacitors0402:C_10p_0402")
		(at 302.26 196.85 0)
		(unit 1)
		(exclude_from_sim no)
		(in_bom yes)
		(on_board yes)
		(dnp no)
		(property "Reference" "C43"
			(at 301.244 198.374 0)
			(effects
				(font
					(size 1.27 1.27)
					(thickness 0.15)
				)
			)
		)
		(property "Value" "C_10p_0402"
			(at 322.58 207.01 0)
			(effects
				(font
					(size 1.27 1.27)
					(thickness 0.15)
				)
				(justify left bottom)
				(hide yes)
			)
		)
		(property "Footprint" "antmicro-footprints:C_0402_1005Metric"
			(at 322.58 209.55 0)
			(effects
				(font
					(size 1.27 1.27)
					(thickness 0.15)
				)
				(justify left bottom)
				(hide yes)
			)
		)
		(property "Datasheet" "https://www.murata.com/products/productdetail?partno=GCM1555C1H100GA16%23"
			(at 322.58 212.09 0)
			(effects
				(font
					(size 1.27 1.27)
					(thickness 0.15)
				)
				(justify left bottom)
				(hide yes)
			)
		)
		(property "Description" "SMD Multilayer Ceramic Capacitor, 10 pF, 50 V, 0402 [1005 Metric], ± 2%, C0G / NP0, GCM"
			(at 302.26 196.85 0)
			(effects
				(font
					(size 1.27 1.27)
				)
				(hide yes)
			)
		)
		(property "MPN" "GCM1555C1H100GA16D"
			(at 322.58 214.63 0)
			(effects
				(font
					(size 1.27 1.27)
					(thickness 0.15)
				)
				(justify left bottom)
				(hide yes)
			)
		)
		(property "Manufacturer" "Murata"
			(at 322.58 217.17 0)
			(effects
				(font
					(size 1.27 1.27)
					(thickness 0.15)
				)
				(justify left bottom)
				(hide yes)
			)
		)
		(property "License" "Apache-2.0"
			(at 322.58 219.71 0)
			(effects
				(font
					(size 1.27 1.27)
					(thickness 0.15)
				)
				(justify left bottom)
				(hide yes)
			)
		)
		(property "Val" "10p"
			(at 307.594 198.374 0)
			(effects
				(font
					(size 1.27 1.27)
					(thickness 0.15)
				)
			)
		)
		(property "Voltage" "50V"
			(at 322.58 224.79 0)
			(effects
				(font
					(size 1.27 1.27)
				)
				(justify left bottom)
				(hide yes)
			)
		)
		(property "Dielectric" "C0G"
			(at 322.58 227.33 0)
			(effects
				(font
					(size 1.27 1.27)
				)
				(justify left bottom)
				(hide yes)
			)
		)
		(property "Author" "Antmicro"
			(at 322.58 222.25 0)
			(effects
				(font
					(size 1.27 1.27)
					(thickness 0.15)
				)
				(justify left bottom)
				(hide yes)
			)
		)
		(pin "1"
		)
		(pin "2"
		)
		(instances
			(project "thunderbolt-to-10gbe-adapter"
				(path ""
					(reference "C43")
					(unit 1)
				)
			)
		)
	)
	(symbol
		(lib_id "antmicropower:GND")
		(at 400.05 210.82 0)
		(unit 1)
		(exclude_from_sim no)
		(in_bom yes)
		(on_board yes)
		(dnp no)
		(property "Reference" "#PWR079"
			(at 400.05 217.17 0)
			(effects
				(font
					(size 1.27 1.27)
				)
				(hide yes)
			)
		)
		(property "Value" "GND"
			(at 400.05 214.63 0)
			(effects
				(font
					(size 1.27 1.27)
				)
			)
		)
		(property "Footprint" ""
			(at 400.05 210.82 0)
			(effects
				(font
					(size 1.27 1.27)
				)
				(hide yes)
			)
		)
		(property "Datasheet" ""
			(at 400.05 210.82 0)
			(effects
				(font
					(size 1.27 1.27)
				)
				(hide yes)
			)
		)
		(property "Description" ""
			(at 400.05 210.82 0)
			(effects
				(font
					(size 1.27 1.27)
				)
				(hide yes)
			)
		)
		(property "Author" "Antmicro"
			(at 408.94 218.44 0)
			(effects
				(font
					(size 1.27 1.27)
					(thickness 0.15)
				)
				(justify left bottom)
				(hide yes)
			)
		)
		(property "License" "Apache-2.0"
			(at 408.94 220.98 0)
			(effects
				(font
					(size 1.27 1.27)
					(thickness 0.15)
				)
				(justify left bottom)
				(hide yes)
			)
		)
		(pin "1"
		)
		(instances
			(project "thunderbolt-to-10gbe-adapter"
				(path ""
					(reference "#PWR079")
					(unit 1)
				)
			)
		)
	)
	(symbol
		(lib_id "antmicroResistors0402:R_10k_0402")
		(at 101.6 231.14 0)
		(unit 1)
		(exclude_from_sim no)
		(in_bom yes)
		(on_board yes)
		(dnp no)
		(property "Reference" "R46"
			(at 100.33 229.87 0)
			(effects
				(font
					(size 1.27 1.27)
					(thickness 0.15)
				)
			)
		)
		(property "Value" "R_10k_0402"
			(at 121.92 243.84 0)
			(effects
				(font
					(size 1.27 1.27)
					(thickness 0.15)
				)
				(justify left bottom)
				(hide yes)
			)
		)
		(property "Footprint" "antmicro-footprints:R_0402_1005Metric"
			(at 121.92 246.38 0)
			(effects
				(font
					(size 1.27 1.27)
					(thickness 0.15)
				)
				(justify left bottom)
				(hide yes)
			)
		)
		(property "Datasheet" "https://www.bourns.com/docs/product-datasheets/cr.pdf"
			(at 121.92 248.92 0)
			(effects
				(font
					(size 1.27 1.27)
					(thickness 0.15)
				)
				(justify left bottom)
				(hide yes)
			)
		)
		(property "Description" "SMD Chip Resistor, 10 kohm, ± 1%, 62.5 mW, 0402 [1005 Metric], Thick Film, General Purpose"
			(at 101.6 231.14 0)
			(effects
				(font
					(size 1.27 1.27)
				)
				(hide yes)
			)
		)
		(property "MPN" "CR0402-FX-1002GLF"
			(at 121.92 251.46 0)
			(effects
				(font
					(size 1.27 1.27)
					(thickness 0.15)
				)
				(justify left bottom)
				(hide yes)
			)
		)
		(property "Manufacturer" "Bourns"
			(at 121.92 254 0)
			(effects
				(font
					(size 1.27 1.27)
					(thickness 0.15)
				)
				(justify left bottom)
				(hide yes)
			)
		)
		(property "License" "Apache-2.0"
			(at 121.92 256.54 0)
			(effects
				(font
					(size 1.27 1.27)
					(thickness 0.15)
				)
				(justify left bottom)
				(hide yes)
			)
		)
		(property "Val" "10k"
			(at 107.95 229.87 0)
			(effects
				(font
					(size 1.27 1.27)
					(thickness 0.15)
				)
			)
		)
		(property "Tolerance" "1%"
			(at 121.92 241.3 0)
			(effects
				(font
					(size 1.27 1.27)
				)
				(justify left bottom)
				(hide yes)
			)
		)
		(property "Author" "Antmicro"
			(at 121.92 259.08 0)
			(effects
				(font
					(size 1.27 1.27)
					(thickness 0.15)
				)
				(justify left bottom)
				(hide yes)
			)
		)
		(pin "1"
		)
		(pin "2"
		)
		(instances
			(project "thunderbolt-to-10gbe-adapter"
				(path ""
					(reference "R46")
					(unit 1)
				)
			)
		)
	)
	(symbol
		(lib_id "antmicroResistors0402:R_14k_0402")
		(at 101.6 208.28 0)
		(unit 1)
		(exclude_from_sim no)
		(in_bom yes)
		(on_board yes)
		(dnp yes)
		(property "Reference" "R42"
			(at 104.14 210.566 0)
			(effects
				(font
					(size 1.27 1.27)
					(thickness 0.15)
				)
			)
		)
		(property "Value" "R_14k_0402"
			(at 121.92 220.98 0)
			(effects
				(font
					(size 1.27 1.27)
					(thickness 0.15)
				)
				(justify left bottom)
				(hide yes)
			)
		)
		(property "Footprint" "antmicro-footprints:R_0402_1005Metric"
			(at 121.92 223.52 0)
			(effects
				(font
					(size 1.27 1.27)
					(thickness 0.15)
				)
				(justify left bottom)
				(hide yes)
			)
		)
		(property "Datasheet" "https://www.bourns.com/docs/product-datasheets/cr.pdf"
			(at 121.92 226.06 0)
			(effects
				(font
					(size 1.27 1.27)
					(thickness 0.15)
				)
				(justify left bottom)
				(hide yes)
			)
		)
		(property "Description" "SMD Chip Resistor, 14 kohm, ± 1%, 100 mW, 0402 [1005 Metric], Thick Film, Precision"
			(at 101.6 208.28 0)
			(effects
				(font
					(size 1.27 1.27)
				)
				(hide yes)
			)
		)
		(property "MPN" "CR0402-FX-1402GLF"
			(at 121.92 228.6 0)
			(effects
				(font
					(size 1.27 1.27)
					(thickness 0.15)
				)
				(justify left bottom)
				(hide yes)
			)
		)
		(property "Manufacturer" "Bourns"
			(at 121.92 231.14 0)
			(effects
				(font
					(size 1.27 1.27)
					(thickness 0.15)
				)
				(justify left bottom)
				(hide yes)
			)
		)
		(property "License" "Apache-2.0"
			(at 121.92 233.68 0)
			(effects
				(font
					(size 1.27 1.27)
					(thickness 0.15)
				)
				(justify left bottom)
				(hide yes)
			)
		)
		(property "Val" "14k"
			(at 104.14 213.106 0)
			(effects
				(font
					(size 1.27 1.27)
					(thickness 0.15)
				)
			)
		)
		(property "Tolerance" "1%"
			(at 121.92 218.44 0)
			(effects
				(font
					(size 1.27 1.27)
				)
				(justify left bottom)
				(hide yes)
			)
		)
		(property "Author" "Antmicro"
			(at 121.92 236.22 0)
			(effects
				(font
					(size 1.27 1.27)
					(thickness 0.15)
				)
				(justify left bottom)
				(hide yes)
			)
		)
		(pin "1"
		)
		(pin "2"
		)
		(instances
			(project "thunderbolt-to-10gbe-adapter"
				(path ""
					(reference "R42")
					(unit 1)
				)
			)
		)
	)
	(symbol
		(lib_id "antmicroResistors0402:R_499R_0402")
		(at 119.38 101.6 0)
		(unit 1)
		(exclude_from_sim no)
		(in_bom yes)
		(on_board yes)
		(dnp no)
		(fields_autoplaced yes)
		(property "Reference" "R56"
			(at 121.92 105.41 0)
			(effects
				(font
					(size 1.27 1.27)
					(thickness 0.15)
				)
			)
		)
		(property "Value" "R_499R_0402"
			(at 139.7 114.3 0)
			(effects
				(font
					(size 1.27 1.27)
					(thickness 0.15)
				)
				(justify left bottom)
				(hide yes)
			)
		)
		(property "Footprint" "antmicro-footprints:R_0402_1005Metric"
			(at 139.7 116.84 0)
			(effects
				(font
					(size 1.27 1.27)
					(thickness 0.15)
				)
				(justify left bottom)
				(hide yes)
			)
		)
		(property "Datasheet" "https://www.mouser.com/datasheet/2/54/cr-1858361.pdf"
			(at 139.7 119.38 0)
			(effects
				(font
					(size 1.27 1.27)
					(thickness 0.15)
				)
				(justify left bottom)
				(hide yes)
			)
		)
		(property "Description" "SMD Chip Resistor, 499 ohm, ± 1%, 63 mW, 0402 [1005 Metric], Thick Film, General Purpose"
			(at 119.38 101.6 0)
			(effects
				(font
					(size 1.27 1.27)
				)
				(hide yes)
			)
		)
		(property "MPN" "CR0402-FX-4990GLF"
			(at 139.7 121.92 0)
			(effects
				(font
					(size 1.27 1.27)
					(thickness 0.15)
				)
				(justify left bottom)
				(hide yes)
			)
		)
		(property "Manufacturer" "Bourns"
			(at 139.7 124.46 0)
			(effects
				(font
					(size 1.27 1.27)
					(thickness 0.15)
				)
				(justify left bottom)
				(hide yes)
			)
		)
		(property "License" "Apache-2.0"
			(at 139.7 127 0)
			(effects
				(font
					(size 1.27 1.27)
					(thickness 0.15)
				)
				(justify left bottom)
				(hide yes)
			)
		)
		(property "Val" "499R"
			(at 121.92 107.95 0)
			(effects
				(font
					(size 1.27 1.27)
					(thickness 0.15)
				)
			)
		)
		(property "Tolerance" "1%"
			(at 139.7 111.76 0)
			(effects
				(font
					(size 1.27 1.27)
				)
				(justify left bottom)
				(hide yes)
			)
		)
		(property "Author" "Antmicro"
			(at 139.7 129.54 0)
			(effects
				(font
					(size 1.27 1.27)
					(thickness 0.15)
				)
				(justify left bottom)
				(hide yes)
			)
		)
		(pin "1"
		)
		(pin "2"
		)
		(instances
			(project "thunderbolt-to-10gbe-adapter"
				(path ""
					(reference "R56")
					(unit 1)
				)
			)
		)
	)
	(symbol
		(lib_id "antmicroCapacitors0402:C_220n_0402")
		(at 105.41 63.5 0)
		(unit 1)
		(exclude_from_sim no)
		(in_bom yes)
		(on_board yes)
		(dnp no)
		(property "Reference" "C36"
			(at 111.125 62.23 0)
			(effects
				(font
					(size 1.27 1.27)
					(thickness 0.15)
				)
			)
		)
		(property "Value" "C_220n_0402"
			(at 125.73 73.66 0)
			(effects
				(font
					(size 1.27 1.27)
					(thickness 0.15)
				)
				(justify left bottom)
				(hide yes)
			)
		)
		(property "Footprint" "antmicro-footprints:C_0402_1005Metric"
			(at 125.73 76.2 0)
			(effects
				(font
					(size 1.27 1.27)
					(thickness 0.15)
				)
				(justify left bottom)
				(hide yes)
			)
		)
		(property "Datasheet" "https://www.yageo.com/en/Chart/Download/pdf/CC0402KRX5R6BB224"
			(at 125.73 78.74 0)
			(effects
				(font
					(size 1.27 1.27)
					(thickness 0.15)
				)
				(justify left bottom)
				(hide yes)
			)
		)
		(property "Description" "SMD Multilayer Ceramic Capacitor, 0.22 µF, 10 V, 0402 [1005 Metric], ± 10%, X5R, CC Series"
			(at 105.41 63.5 0)
			(effects
				(font
					(size 1.27 1.27)
				)
				(hide yes)
			)
		)
		(property "MPN" "CC0402KRX5R6BB224"
			(at 125.73 81.28 0)
			(effects
				(font
					(size 1.27 1.27)
					(thickness 0.15)
				)
				(justify left bottom)
				(hide yes)
			)
		)
		(property "Manufacturer" "YAGEO"
			(at 125.73 83.82 0)
			(effects
				(font
					(size 1.27 1.27)
					(thickness 0.15)
				)
				(justify left bottom)
				(hide yes)
			)
		)
		(property "License" "Apache-2.0"
			(at 125.73 86.36 0)
			(effects
				(font
					(size 1.27 1.27)
					(thickness 0.15)
				)
				(justify left bottom)
				(hide yes)
			)
		)
		(property "Val" "220n"
			(at 111.125 64.77 0)
			(effects
				(font
					(size 1.27 1.27)
					(thickness 0.15)
				)
			)
		)
		(property "Voltage" ""
			(at 125.73 91.44 0)
			(effects
				(font
					(size 1.27 1.27)
				)
				(justify left bottom)
				(hide yes)
			)
		)
		(property "Dielectric" ""
			(at 125.73 93.98 0)
			(effects
				(font
					(size 1.27 1.27)
				)
				(justify left bottom)
				(hide yes)
			)
		)
		(property "Author" "Antmicro"
			(at 125.73 88.9 0)
			(effects
				(font
					(size 1.27 1.27)
					(thickness 0.15)
				)
				(justify left bottom)
				(hide yes)
			)
		)
		(pin "1"
		)
		(pin "2"
		)
		(instances
			(project "thunderbolt-to-10gbe-adapter"
				(path ""
					(reference "C36")
					(unit 1)
				)
			)
		)
	)
	(symbol
		(lib_id "antmicroResistors0402:R_100k_0402")
		(at 101.6 259.08 0)
		(unit 1)
		(exclude_from_sim no)
		(in_bom yes)
		(on_board yes)
		(dnp no)
		(property "Reference" "R53"
			(at 100.33 257.81 0)
			(effects
				(font
					(size 1.27 1.27)
					(thickness 0.15)
				)
			)
		)
		(property "Value" "R_100k_0402"
			(at 121.92 271.78 0)
			(effects
				(font
					(size 1.27 1.27)
					(thickness 0.15)
				)
				(justify left bottom)
				(hide yes)
			)
		)
		(property "Footprint" "antmicro-footprints:R_0402_1005Metric"
			(at 121.92 274.32 0)
			(effects
				(font
					(size 1.27 1.27)
					(thickness 0.15)
				)
				(justify left bottom)
				(hide yes)
			)
		)
		(property "Datasheet" "https://www.bourns.com/docs/product-datasheets/cr.pdf"
			(at 121.92 276.86 0)
			(effects
				(font
					(size 1.27 1.27)
					(thickness 0.15)
				)
				(justify left bottom)
				(hide yes)
			)
		)
		(property "Description" "SMD Chip Resistor, 100 kohm, ± 1%, 62.5 mW, 0402 [1005 Metric], Thick Film, General Purpose"
			(at 101.6 259.08 0)
			(effects
				(font
					(size 1.27 1.27)
				)
				(hide yes)
			)
		)
		(property "MPN" "CR0402-FX-1003GLF"
			(at 121.92 279.4 0)
			(effects
				(font
					(size 1.27 1.27)
					(thickness 0.15)
				)
				(justify left bottom)
				(hide yes)
			)
		)
		(property "Manufacturer" "Bourns"
			(at 121.92 281.94 0)
			(effects
				(font
					(size 1.27 1.27)
					(thickness 0.15)
				)
				(justify left bottom)
				(hide yes)
			)
		)
		(property "License" "Apache-2.0"
			(at 121.92 284.48 0)
			(effects
				(font
					(size 1.27 1.27)
					(thickness 0.15)
				)
				(justify left bottom)
				(hide yes)
			)
		)
		(property "Val" "100k"
			(at 108.585 257.81 0)
			(effects
				(font
					(size 1.27 1.27)
					(thickness 0.15)
				)
			)
		)
		(property "Tolerance" "1%"
			(at 121.92 269.24 0)
			(effects
				(font
					(size 1.27 1.27)
				)
				(justify left bottom)
				(hide yes)
			)
		)
		(property "Author" "Antmicro"
			(at 121.92 287.02 0)
			(effects
				(font
					(size 1.27 1.27)
					(thickness 0.15)
				)
				(justify left bottom)
				(hide yes)
			)
		)
		(pin "1"
		)
		(pin "2"
		)
		(instances
			(project "thunderbolt-to-10gbe-adapter"
				(path ""
					(reference "R53")
					(unit 1)
				)
			)
		)
	)
	(symbol
		(lib_id "antmicroResistors0402:R_14k_0402")
		(at 33.02 269.24 0)
		(unit 1)
		(exclude_from_sim no)
		(in_bom yes)
		(on_board yes)
		(dnp yes)
		(fields_autoplaced yes)
		(property "Reference" "R40"
			(at 35.56 273.05 0)
			(effects
				(font
					(size 1.27 1.27)
					(thickness 0.15)
				)
			)
		)
		(property "Value" "R_14k_0402"
			(at 53.34 281.94 0)
			(effects
				(font
					(size 1.27 1.27)
					(thickness 0.15)
				)
				(justify left bottom)
				(hide yes)
			)
		)
		(property "Footprint" "antmicro-footprints:R_0402_1005Metric"
			(at 53.34 284.48 0)
			(effects
				(font
					(size 1.27 1.27)
					(thickness 0.15)
				)
				(justify left bottom)
				(hide yes)
			)
		)
		(property "Datasheet" "https://www.bourns.com/docs/product-datasheets/cr.pdf"
			(at 53.34 287.02 0)
			(effects
				(font
					(size 1.27 1.27)
					(thickness 0.15)
				)
				(justify left bottom)
				(hide yes)
			)
		)
		(property "Description" "SMD Chip Resistor, 14 kohm, ± 1%, 100 mW, 0402 [1005 Metric], Thick Film, Precision"
			(at 33.02 269.24 0)
			(effects
				(font
					(size 1.27 1.27)
				)
				(hide yes)
			)
		)
		(property "MPN" "CR0402-FX-1402GLF"
			(at 53.34 289.56 0)
			(effects
				(font
					(size 1.27 1.27)
					(thickness 0.15)
				)
				(justify left bottom)
				(hide yes)
			)
		)
		(property "Manufacturer" "Bourns"
			(at 53.34 292.1 0)
			(effects
				(font
					(size 1.27 1.27)
					(thickness 0.15)
				)
				(justify left bottom)
				(hide yes)
			)
		)
		(property "License" "Apache-2.0"
			(at 53.34 294.64 0)
			(effects
				(font
					(size 1.27 1.27)
					(thickness 0.15)
				)
				(justify left bottom)
				(hide yes)
			)
		)
		(property "Val" "14k"
			(at 35.56 275.59 0)
			(effects
				(font
					(size 1.27 1.27)
					(thickness 0.15)
				)
			)
		)
		(property "Tolerance" "1%"
			(at 53.34 279.4 0)
			(effects
				(font
					(size 1.27 1.27)
				)
				(justify left bottom)
				(hide yes)
			)
		)
		(property "Author" "Antmicro"
			(at 53.34 297.18 0)
			(effects
				(font
					(size 1.27 1.27)
					(thickness 0.15)
				)
				(justify left bottom)
				(hide yes)
			)
		)
		(pin "1"
		)
		(pin "2"
		)
		(instances
			(project "thunderbolt-to-10gbe-adapter"
				(path ""
					(reference "R40")
					(unit 1)
				)
			)
		)
	)
	(symbol
		(lib_id "antmicroResistors0402:R_100k_0402")
		(at 101.6 233.68 0)
		(unit 1)
		(exclude_from_sim no)
		(in_bom yes)
		(on_board yes)
		(dnp no)
		(property "Reference" "R47"
			(at 100.33 232.41 0)
			(effects
				(font
					(size 1.27 1.27)
					(thickness 0.15)
				)
			)
		)
		(property "Value" "R_100k_0402"
			(at 121.92 246.38 0)
			(effects
				(font
					(size 1.27 1.27)
					(thickness 0.15)
				)
				(justify left bottom)
				(hide yes)
			)
		)
		(property "Footprint" "antmicro-footprints:R_0402_1005Metric"
			(at 121.92 248.92 0)
			(effects
				(font
					(size 1.27 1.27)
					(thickness 0.15)
				)
				(justify left bottom)
				(hide yes)
			)
		)
		(property "Datasheet" "https://www.bourns.com/docs/product-datasheets/cr.pdf"
			(at 121.92 251.46 0)
			(effects
				(font
					(size 1.27 1.27)
					(thickness 0.15)
				)
				(justify left bottom)
				(hide yes)
			)
		)
		(property "Description" "SMD Chip Resistor, 100 kohm, ± 1%, 62.5 mW, 0402 [1005 Metric], Thick Film, General Purpose"
			(at 101.6 233.68 0)
			(effects
				(font
					(size 1.27 1.27)
				)
				(hide yes)
			)
		)
		(property "MPN" "CR0402-FX-1003GLF"
			(at 121.92 254 0)
			(effects
				(font
					(size 1.27 1.27)
					(thickness 0.15)
				)
				(justify left bottom)
				(hide yes)
			)
		)
		(property "Manufacturer" "Bourns"
			(at 121.92 256.54 0)
			(effects
				(font
					(size 1.27 1.27)
					(thickness 0.15)
				)
				(justify left bottom)
				(hide yes)
			)
		)
		(property "License" "Apache-2.0"
			(at 121.92 259.08 0)
			(effects
				(font
					(size 1.27 1.27)
					(thickness 0.15)
				)
				(justify left bottom)
				(hide yes)
			)
		)
		(property "Val" "100k"
			(at 108.585 232.41 0)
			(effects
				(font
					(size 1.27 1.27)
					(thickness 0.15)
				)
			)
		)
		(property "Tolerance" "1%"
			(at 121.92 243.84 0)
			(effects
				(font
					(size 1.27 1.27)
				)
				(justify left bottom)
				(hide yes)
			)
		)
		(property "Author" "Antmicro"
			(at 121.92 261.62 0)
			(effects
				(font
					(size 1.27 1.27)
					(thickness 0.15)
				)
				(justify left bottom)
				(hide yes)
			)
		)
		(pin "1"
		)
		(pin "2"
		)
		(instances
			(project "thunderbolt-to-10gbe-adapter"
				(path ""
					(reference "R47")
					(unit 1)
				)
			)
		)
	)
	(symbol
		(lib_id "antmicropower:GND")
		(at 243.84 129.54 0)
		(unit 1)
		(exclude_from_sim no)
		(in_bom yes)
		(on_board yes)
		(dnp no)
		(property "Reference" "#PWR069"
			(at 243.84 135.89 0)
			(effects
				(font
					(size 1.27 1.27)
				)
				(hide yes)
			)
		)
		(property "Value" "GND"
			(at 243.84 133.35 0)
			(effects
				(font
					(size 1.27 1.27)
				)
			)
		)
		(property "Footprint" ""
			(at 243.84 129.54 0)
			(effects
				(font
					(size 1.27 1.27)
				)
				(hide yes)
			)
		)
		(property "Datasheet" ""
			(at 243.84 129.54 0)
			(effects
				(font
					(size 1.27 1.27)
				)
				(hide yes)
			)
		)
		(property "Description" ""
			(at 243.84 129.54 0)
			(effects
				(font
					(size 1.27 1.27)
				)
				(hide yes)
			)
		)
		(property "Author" "Antmicro"
			(at 252.73 137.16 0)
			(effects
				(font
					(size 1.27 1.27)
					(thickness 0.15)
				)
				(justify left bottom)
				(hide yes)
			)
		)
		(property "License" "Apache-2.0"
			(at 252.73 139.7 0)
			(effects
				(font
					(size 1.27 1.27)
					(thickness 0.15)
				)
				(justify left bottom)
				(hide yes)
			)
		)
		(pin "1"
		)
		(instances
			(project "thunderbolt-to-10gbe-adapter"
				(path ""
					(reference "#PWR069")
					(unit 1)
				)
			)
		)
	)
	(symbol
		(lib_id "antmicroInterfaceControllers:JHL6340SLLSQ")
		(at 41.91 165.1 0)
		(unit 3)
		(exclude_from_sim no)
		(in_bom yes)
		(on_board yes)
		(dnp no)
		(fields_autoplaced yes)
		(property "Reference" "U4"
			(at 69.85 156.845 0)
			(effects
				(font
					(size 1.27 1.27)
					(thickness 0.15)
				)
			)
		)
		(property "Value" "JHL6340SLLSQ"
			(at 113.03 167.64 0)
			(effects
				(font
					(size 1.27 1.27)
					(thickness 0.15)
				)
				(justify left bottom)
				(hide yes)
			)
		)
		(property "Footprint" "antmicro-footprints:JHL6340SLLSQ"
			(at 113.03 170.18 0)
			(effects
				(font
					(size 1.27 1.27)
					(thickness 0.15)
				)
				(justify left bottom)
				(hide yes)
			)
		)
		(property "Datasheet" "https://www.thunderbolttechnology.net/sites/default/files/18-241_ThunderboltController_Brief_HI.pdf"
			(at 113.03 172.72 0)
			(effects
				(font
					(size 1.27 1.27)
					(thickness 0.15)
				)
				(justify left bottom)
				(hide yes)
			)
		)
		(property "Description" "Thunderbolt™ 3 Controller, I/O"
			(at 41.91 165.1 0)
			(effects
				(font
					(size 1.27 1.27)
				)
				(hide yes)
			)
		)
		(property "Manufacturer" "Intel"
			(at 113.03 175.26 0)
			(effects
				(font
					(size 1.27 1.27)
					(thickness 0.15)
				)
				(justify left bottom)
				(hide yes)
			)
		)
		(property "MPN" "JHL6340SLLSQ"
			(at 69.85 159.385 0)
			(effects
				(font
					(size 1.27 1.27)
					(thickness 0.15)
				)
			)
		)
		(property "Author" "Antmicro"
			(at 113.03 180.34 0)
			(effects
				(font
					(size 1.27 1.27)
					(thickness 0.15)
				)
				(justify left bottom)
				(hide yes)
			)
		)
		(property "License" "Apache-2.0"
			(at 113.03 182.88 0)
			(effects
				(font
					(size 1.27 1.27)
					(thickness 0.15)
				)
				(justify left bottom)
				(hide yes)
			)
		)
		(pin "V5"
		)
		(pin "Y9"
		)
		(pin "AC5"
		)
		(pin "F12"
		)
		(pin "L13"
		)
		(pin "A13"
		)
		(pin "T23"
		)
		(pin "AA2"
		)
		(pin "L22"
		)
		(pin "R16"
		)
		(pin "N13"
		)
		(pin "D9"
		)
		(pin "T2"
		)
		(pin "R12"
		)
		(pin "U1"
		)
		(pin "R23"
		)
		(pin "J23"
		)
		(pin "T22"
		)
		(pin "L23"
		)
		(pin "B3"
		)
		(pin "V4"
		)
		(pin "N8"
		)
		(pin "AB11"
		)
		(pin "AB4"
		)
		(pin "M6"
		)
		(pin "K22"
		)
		(pin "R5"
		)
		(pin "L15"
		)
		(pin "F13"
		)
		(pin "L12"
		)
		(pin "H20"
		)
		(pin "V15"
		)
		(pin "V22"
		)
		(pin "V19"
		)
		(pin "P23"
		)
		(pin "M18"
		)
		(pin "A4"
		)
		(pin "A9"
		)
		(pin "M23"
		)
		(pin "Y8"
		)
		(pin "Y4"
		)
		(pin "N5"
		)
		(pin "T5"
		)
		(pin "W1"
		)
		(pin "Y11"
		)
		(pin "Y5"
		)
		(pin "B22"
		)
		(pin "B6"
		)
		(pin "V8"
		)
		(pin "V1"
		)
		(pin "A17"
		)
		(pin "Y2"
		)
		(pin "W2"
		)
		(pin "R22"
		)
		(pin "N6"
		)
		(pin "F16"
		)
		(pin "AB13"
		)
		(pin "H4"
		)
		(pin "F22"
		)
		(pin "R4"
		)
		(pin "F23"
		)
		(pin "W11"
		)
		(pin "D13"
		)
		(pin "AC10"
		)
		(pin "M9"
		)
		(pin "V2"
		)
		(pin "L19"
		)
		(pin "T18"
		)
		(pin "L20"
		)
		(pin "H8"
		)
		(pin "AB7"
		)
		(pin "Y23"
		)
		(pin "K1"
		)
		(pin "AC7"
		)
		(pin "H18"
		)
		(pin "C1"
		)
		(pin "N1"
		)
		(pin "AB5"
		)
		(pin "J5"
		)
		(pin "R15"
		)
		(pin "M13"
		)
		(pin "D1"
		)
		(pin "E20"
		)
		(pin "AC11"
		)
		(pin "A5"
		)
		(pin "AB15"
		)
		(pin "L8"
		)
		(pin "D6"
		)
		(pin "D19"
		)
		(pin "V6"
		)
		(pin "N19"
		)
		(pin "T11"
		)
		(pin "W8"
		)
		(pin "C22"
		)
		(pin "H19"
		)
		(pin "L11"
		)
		(pin "AC13"
		)
		(pin "D2"
		)
		(pin "K23"
		)
		(pin "L2"
		)
		(pin "A7"
		)
		(pin "H16"
		)
		(pin "Y16"
		)
		(pin "V12"
		)
		(pin "AB9"
		)
		(pin "M20"
		)
		(pin "N20"
		)
		(pin "R19"
		)
		(pin "U22"
		)
		(pin "AB21"
		)
		(pin "E4"
		)
		(pin "R6"
		)
		(pin "R20"
		)
		(pin "AC1"
		)
		(pin "G2"
		)
		(pin "M8"
		)
		(pin "M16"
		)
		(pin "V20"
		)
		(pin "F18"
		)
		(pin "AB3"
		)
		(pin "AA1"
		)
		(pin "D22"
		)
		(pin "V11"
		)
		(pin "T1"
		)
		(pin "V18"
		)
		(pin "B9"
		)
		(pin "J9"
		)
		(pin "M5"
		)
		(pin "H15"
		)
		(pin "M12"
		)
		(pin "M15"
		)
		(pin "AC9"
		)
		(pin "W23"
		)
		(pin "V9"
		)
		(pin "B8"
		)
		(pin "N16"
		)
		(pin "B14"
		)
		(pin "AC23"
		)
		(pin "W18"
		)
		(pin "M1"
		)
		(pin "N15"
		)
		(pin "AB17"
		)
		(pin "U23"
		)
		(pin "Y22"
		)
		(pin "L9"
		)
		(pin "T13"
		)
		(pin "F11"
		)
		(pin "N4"
		)
		(pin "F19"
		)
		(pin "W6"
		)
		(pin "F15"
		)
		(pin "B7"
		)
		(pin "Y1"
		)
		(pin "A6"
		)
		(pin "B2"
		)
		(pin "B4"
		)
		(pin "R13"
		)
		(pin "K2"
		)
		(pin "N18"
		)
		(pin "B13"
		)
		(pin "T19"
		)
		(pin "W22"
		)
		(pin "H23"
		)
		(pin "T4"
		)
		(pin "L18"
		)
		(pin "E19"
		)
		(pin "H2"
		)
		(pin "L1"
		)
		(pin "F20"
		)
		(pin "B23"
		)
		(pin "R8"
		)
		(pin "M22"
		)
		(pin "F2"
		)
		(pin "E18"
		)
		(pin "R2"
		)
		(pin "W4"
		)
		(pin "B5"
		)
		(pin "W19"
		)
		(pin "N22"
		)
		(pin "D5"
		)
		(pin "W20"
		)
		(pin "W12"
		)
		(pin "B11"
		)
		(pin "R11"
		)
		(pin "E2"
		)
		(pin "D18"
		)
		(pin "T8"
		)
		(pin "L5"
		)
		(pin "M4"
		)
		(pin "T20"
		)
		(pin "A3"
		)
		(pin "AC3"
		)
		(pin "A19"
		)
		(pin "L16"
		)
		(pin "F4"
		)
		(pin "T12"
		)
		(pin "Y18"
		)
		(pin "T16"
		)
		(pin "AB19"
		)
		(pin "B12"
		)
		(pin "E23"
		)
		(pin "E1"
		)
		(pin "T6"
		)
		(pin "Y19"
		)
		(pin "T15"
		)
		(pin "P22"
		)
		(pin "AB16"
		)
		(pin "AC4"
		)
		(pin "D15"
		)
		(pin "G1"
		)
		(pin "A8"
		)
		(pin "Y12"
		)
		(pin "J4"
		)
		(pin "J1"
		)
		(pin "E22"
		)
		(pin "D20"
		)
		(pin "M2"
		)
		(pin "V23"
		)
		(pin "AB10"
		)
		(pin "AB2"
		)
		(pin "AC15"
		)
		(pin "D23"
		)
		(pin "A23"
		)
		(pin "C23"
		)
		(pin "J2"
		)
		(pin "A21"
		)
		(pin "F1"
		)
		(pin "H5"
		)
		(pin "N11"
		)
		(pin "B20"
		)
		(pin "H22"
		)
		(pin "AA23"
		)
		(pin "E13"
		)
		(pin "J12"
		)
		(pin "W9"
		)
		(pin "H9"
		)
		(pin "B19"
		)
		(pin "AB8"
		)
		(pin "AB22"
		)
		(pin "AB6"
		)
		(pin "AB20"
		)
		(pin "AC2"
		)
		(pin "E9"
		)
		(pin "J11"
		)
		(pin "L4"
		)
		(pin "J8"
		)
		(pin "AC22"
		)
		(pin "J13"
		)
		(pin "N12"
		)
		(pin "J15"
		)
		(pin "B18"
		)
		(pin "Y15"
		)
		(pin "U2"
		)
		(pin "AC12"
		)
		(pin "D16"
		)
		(pin "AB14"
		)
		(pin "AC6"
		)
		(pin "A14"
		)
		(pin "V13"
		)
		(pin "G22"
		)
		(pin "Y13"
		)
		(pin "B16"
		)
		(pin "AB18"
		)
		(pin "B17"
		)
		(pin "A20"
		)
		(pin "AB12"
		)
		(pin "R1"
		)
		(pin "AC20"
		)
		(pin "H12"
		)
		(pin "A2"
		)
		(pin "F5"
		)
		(pin "E6"
		)
		(pin "A10"
		)
		(pin "A12"
		)
		(pin "H11"
		)
		(pin "F9"
		)
		(pin "A1"
		)
		(pin "AB1"
		)
		(pin "E8"
		)
		(pin "A11"
		)
		(pin "L6"
		)
		(pin "B21"
		)
		(pin "AB23"
		)
		(pin "W13"
		)
		(pin "P2"
		)
		(pin "W16"
		)
		(pin "AC16"
		)
		(pin "H6"
		)
		(pin "Y6"
		)
		(pin "A15"
		)
		(pin "J6"
		)
		(pin "V16"
		)
		(pin "N9"
		)
		(pin "AC21"
		)
		(pin "J19"
		)
		(pin "J20"
		)
		(pin "AC17"
		)
		(pin "AC19"
		)
		(pin "M11"
		)
		(pin "D4"
		)
		(pin "P1"
		)
		(pin "W5"
		)
		(pin "R18"
		)
		(pin "E16"
		)
		(pin "N23"
		)
		(pin "A22"
		)
		(pin "R9"
		)
		(pin "D8"
		)
		(pin "E15"
		)
		(pin "M19"
		)
		(pin "Y20"
		)
		(pin "T9"
		)
		(pin "H13"
		)
		(pin "W15"
		)
		(pin "B10"
		)
		(pin "AC14"
		)
		(pin "AC18"
		)
		(pin "C2"
		)
		(pin "E5"
		)
		(pin "J22"
		)
		(pin "J18"
		)
		(pin "J16"
		)
		(pin "AC8"
		)
		(pin "B1"
		)
		(pin "N2"
		)
		(pin "E11"
		)
		(pin "A18"
		)
		(pin "H1"
		)
		(pin "G23"
		)
		(pin "A16"
		)
		(pin "D11"
		)
		(pin "B15"
		)
		(pin "F8"
		)
		(pin "E12"
		)
		(pin "AA22"
		)
		(pin "D12"
		)
		(pin "F6"
		)
		(instances
			(project "thunderbolt-to-10gbe-adapter"
				(path ""
					(reference "U4")
					(unit 3)
				)
			)
		)
	)
	(symbol
		(lib_id "antmicroResistors0402:R_1M_0402")
		(at 101.6 236.22 0)
		(unit 1)
		(exclude_from_sim no)
		(in_bom yes)
		(on_board yes)
		(dnp no)
		(property "Reference" "R48"
			(at 100.33 234.95 0)
			(effects
				(font
					(size 1.27 1.27)
					(thickness 0.15)
				)
			)
		)
		(property "Value" "R_1M_0402"
			(at 121.92 248.92 0)
			(effects
				(font
					(size 1.27 1.27)
					(thickness 0.15)
				)
				(justify left bottom)
				(hide yes)
			)
		)
		(property "Footprint" "antmicro-footprints:R_0402_1005Metric"
			(at 121.92 251.46 0)
			(effects
				(font
					(size 1.27 1.27)
					(thickness 0.15)
				)
				(justify left bottom)
				(hide yes)
			)
		)
		(property "Datasheet" "https://www.bourns.com/docs/product-datasheets/cr.pdf"
			(at 121.92 254 0)
			(effects
				(font
					(size 1.27 1.27)
					(thickness 0.15)
				)
				(justify left bottom)
				(hide yes)
			)
		)
		(property "Description" "SMD Chip Resistor, 1 Mohm, ± 1%, 62.5 mW, 0402 [1005 Metric], Thick Film, General Purpose"
			(at 101.6 236.22 0)
			(effects
				(font
					(size 1.27 1.27)
				)
				(hide yes)
			)
		)
		(property "MPN" "CR0402-FX-1004GLF"
			(at 121.92 256.54 0)
			(effects
				(font
					(size 1.27 1.27)
					(thickness 0.15)
				)
				(justify left bottom)
				(hide yes)
			)
		)
		(property "Manufacturer" "Bourns"
			(at 121.92 259.08 0)
			(effects
				(font
					(size 1.27 1.27)
					(thickness 0.15)
				)
				(justify left bottom)
				(hide yes)
			)
		)
		(property "License" "Apache-2.0"
			(at 121.92 261.62 0)
			(effects
				(font
					(size 1.27 1.27)
					(thickness 0.15)
				)
				(justify left bottom)
				(hide yes)
			)
		)
		(property "Val" "1M"
			(at 107.95 234.95 0)
			(effects
				(font
					(size 1.27 1.27)
					(thickness 0.15)
				)
			)
		)
		(property "Tolerance" "1%"
			(at 121.92 246.38 0)
			(effects
				(font
					(size 1.27 1.27)
				)
				(justify left bottom)
				(hide yes)
			)
		)
		(property "Author" "Antmicro"
			(at 121.92 264.16 0)
			(effects
				(font
					(size 1.27 1.27)
					(thickness 0.15)
				)
				(justify left bottom)
				(hide yes)
			)
		)
		(pin "1"
		)
		(pin "2"
		)
		(instances
			(project "thunderbolt-to-10gbe-adapter"
				(path ""
					(reference "R48")
					(unit 1)
				)
			)
		)
	)
	(symbol
		(lib_id "antmicroResistors0402:R_10k_0402")
		(at 189.23 184.15 0)
		(unit 1)
		(exclude_from_sim no)
		(in_bom yes)
		(on_board yes)
		(dnp no)
		(property "Reference" "R62"
			(at 195.58 182.88 0)
			(effects
				(font
					(size 1.27 1.27)
					(thickness 0.15)
				)
			)
		)
		(property "Value" "R_10k_0402"
			(at 209.55 196.85 0)
			(effects
				(font
					(size 1.27 1.27)
					(thickness 0.15)
				)
				(justify left bottom)
				(hide yes)
			)
		)
		(property "Footprint" "antmicro-footprints:R_0402_1005Metric"
			(at 209.55 199.39 0)
			(effects
				(font
					(size 1.27 1.27)
					(thickness 0.15)
				)
				(justify left bottom)
				(hide yes)
			)
		)
		(property "Datasheet" "https://www.bourns.com/docs/product-datasheets/cr.pdf"
			(at 209.55 201.93 0)
			(effects
				(font
					(size 1.27 1.27)
					(thickness 0.15)
				)
				(justify left bottom)
				(hide yes)
			)
		)
		(property "Description" "SMD Chip Resistor, 10 kohm, ± 1%, 62.5 mW, 0402 [1005 Metric], Thick Film, General Purpose"
			(at 189.23 184.15 0)
			(effects
				(font
					(size 1.27 1.27)
				)
				(hide yes)
			)
		)
		(property "MPN" "CR0402-FX-1002GLF"
			(at 209.55 204.47 0)
			(effects
				(font
					(size 1.27 1.27)
					(thickness 0.15)
				)
				(justify left bottom)
				(hide yes)
			)
		)
		(property "Manufacturer" "Bourns"
			(at 209.55 207.01 0)
			(effects
				(font
					(size 1.27 1.27)
					(thickness 0.15)
				)
				(justify left bottom)
				(hide yes)
			)
		)
		(property "License" "Apache-2.0"
			(at 209.55 209.55 0)
			(effects
				(font
					(size 1.27 1.27)
					(thickness 0.15)
				)
				(justify left bottom)
				(hide yes)
			)
		)
		(property "Val" "10k"
			(at 187.96 182.88 0)
			(effects
				(font
					(size 1.27 1.27)
					(thickness 0.15)
				)
			)
		)
		(property "Tolerance" "1%"
			(at 209.55 194.31 0)
			(effects
				(font
					(size 1.27 1.27)
				)
				(justify left bottom)
				(hide yes)
			)
		)
		(property "Author" "Antmicro"
			(at 209.55 212.09 0)
			(effects
				(font
					(size 1.27 1.27)
					(thickness 0.15)
				)
				(justify left bottom)
				(hide yes)
			)
		)
		(pin "1"
		)
		(pin "2"
		)
		(instances
			(project "thunderbolt-to-10gbe-adapter"
				(path ""
					(reference "R62")
					(unit 1)
				)
			)
		)
	)
	(symbol
		(lib_id "antmicroResistors0402:R_100k_0402")
		(at 101.6 223.52 0)
		(unit 1)
		(exclude_from_sim no)
		(in_bom yes)
		(on_board yes)
		(dnp no)
		(property "Reference" "R43"
			(at 100.33 222.25 0)
			(effects
				(font
					(size 1.27 1.27)
					(thickness 0.15)
				)
			)
		)
		(property "Value" "R_100k_0402"
			(at 121.92 236.22 0)
			(effects
				(font
					(size 1.27 1.27)
					(thickness 0.15)
				)
				(justify left bottom)
				(hide yes)
			)
		)
		(property "Footprint" "antmicro-footprints:R_0402_1005Metric"
			(at 121.92 238.76 0)
			(effects
				(font
					(size 1.27 1.27)
					(thickness 0.15)
				)
				(justify left bottom)
				(hide yes)
			)
		)
		(property "Datasheet" "https://www.bourns.com/docs/product-datasheets/cr.pdf"
			(at 121.92 241.3 0)
			(effects
				(font
					(size 1.27 1.27)
					(thickness 0.15)
				)
				(justify left bottom)
				(hide yes)
			)
		)
		(property "Description" "SMD Chip Resistor, 100 kohm, ± 1%, 62.5 mW, 0402 [1005 Metric], Thick Film, General Purpose"
			(at 101.6 223.52 0)
			(effects
				(font
					(size 1.27 1.27)
				)
				(hide yes)
			)
		)
		(property "MPN" "CR0402-FX-1003GLF"
			(at 121.92 243.84 0)
			(effects
				(font
					(size 1.27 1.27)
					(thickness 0.15)
				)
				(justify left bottom)
				(hide yes)
			)
		)
		(property "Manufacturer" "Bourns"
			(at 121.92 246.38 0)
			(effects
				(font
					(size 1.27 1.27)
					(thickness 0.15)
				)
				(justify left bottom)
				(hide yes)
			)
		)
		(property "License" "Apache-2.0"
			(at 121.92 248.92 0)
			(effects
				(font
					(size 1.27 1.27)
					(thickness 0.15)
				)
				(justify left bottom)
				(hide yes)
			)
		)
		(property "Val" "100k"
			(at 108.585 222.25 0)
			(effects
				(font
					(size 1.27 1.27)
					(thickness 0.15)
				)
			)
		)
		(property "Tolerance" "1%"
			(at 121.92 233.68 0)
			(effects
				(font
					(size 1.27 1.27)
				)
				(justify left bottom)
				(hide yes)
			)
		)
		(property "Author" "Antmicro"
			(at 121.92 251.46 0)
			(effects
				(font
					(size 1.27 1.27)
					(thickness 0.15)
				)
				(justify left bottom)
				(hide yes)
			)
		)
		(pin "1"
		)
		(pin "2"
		)
		(instances
			(project "thunderbolt-to-10gbe-adapter"
				(path ""
					(reference "R43")
					(unit 1)
				)
			)
		)
	)
	(symbol
		(lib_id "antmicropower:+3V3")
		(at 127 245.11 0)
		(unit 1)
		(exclude_from_sim no)
		(in_bom yes)
		(on_board yes)
		(dnp no)
		(property "Reference" "#PWR066"
			(at 142.24 245.11 0)
			(effects
				(font
					(size 1.27 1.27)
					(thickness 0.15)
				)
				(justify left bottom)
				(hide yes)
			)
		)
		(property "Value" "+3V3_TB"
			(at 127 241.3 0)
			(effects
				(font
					(size 1.27 1.27)
					(thickness 0.15)
				)
			)
		)
		(property "Footprint" ""
			(at 142.24 252.73 0)
			(effects
				(font
					(size 1.27 1.27)
					(thickness 0.15)
				)
				(justify left bottom)
				(hide yes)
			)
		)
		(property "Datasheet" ""
			(at 142.24 255.27 0)
			(effects
				(font
					(size 1.27 1.27)
					(thickness 0.15)
				)
				(justify left bottom)
				(hide yes)
			)
		)
		(property "Description" ""
			(at 142.24 257.81 0)
			(effects
				(font
					(size 1.27 1.27)
				)
				(justify left bottom)
				(hide yes)
			)
		)
		(property "Author" "Antmicro"
			(at 142.24 247.65 0)
			(effects
				(font
					(size 1.27 1.27)
					(thickness 0.15)
				)
				(justify left bottom)
				(hide yes)
			)
		)
		(property "License" "Apache-2.0"
			(at 142.24 250.19 0)
			(effects
				(font
					(size 1.27 1.27)
					(thickness 0.15)
				)
				(justify left bottom)
				(hide yes)
			)
		)
		(pin "1"
		)
		(instances
			(project "thunderbolt-to-10gbe-adapter"
				(path ""
					(reference "#PWR066")
					(unit 1)
				)
			)
		)
	)
	(symbol
		(lib_id "antmicropower:GND")
		(at 113.03 237.49 0)
		(unit 1)
		(exclude_from_sim no)
		(in_bom yes)
		(on_board yes)
		(dnp no)
		(property "Reference" "#PWR063"
			(at 113.03 243.84 0)
			(effects
				(font
					(size 1.27 1.27)
				)
				(hide yes)
			)
		)
		(property "Value" "GND"
			(at 113.03 241.3 0)
			(effects
				(font
					(size 1.27 1.27)
				)
			)
		)
		(property "Footprint" ""
			(at 113.03 237.49 0)
			(effects
				(font
					(size 1.27 1.27)
				)
				(hide yes)
			)
		)
		(property "Datasheet" ""
			(at 113.03 237.49 0)
			(effects
				(font
					(size 1.27 1.27)
				)
				(hide yes)
			)
		)
		(property "Description" ""
			(at 113.03 237.49 0)
			(effects
				(font
					(size 1.27 1.27)
				)
				(hide yes)
			)
		)
		(property "Author" "Antmicro"
			(at 121.92 245.11 0)
			(effects
				(font
					(size 1.27 1.27)
					(thickness 0.15)
				)
				(justify left bottom)
				(hide yes)
			)
		)
		(property "License" "Apache-2.0"
			(at 121.92 247.65 0)
			(effects
				(font
					(size 1.27 1.27)
					(thickness 0.15)
				)
				(justify left bottom)
				(hide yes)
			)
		)
		(pin "1"
		)
		(instances
			(project "thunderbolt-to-10gbe-adapter"
				(path ""
					(reference "#PWR063")
					(unit 1)
				)
			)
		)
	)
	(symbol
		(lib_id "antmicroCapacitors0402:C_100n_0402")
		(at 100.33 76.2 0)
		(unit 1)
		(exclude_from_sim no)
		(in_bom yes)
		(on_board yes)
		(dnp no)
		(property "Reference" "C35"
			(at 99.695 74.93 0)
			(effects
				(font
					(size 1.27 1.27)
					(thickness 0.15)
				)
			)
		)
		(property "Value" "C_100n_0402"
			(at 120.65 86.36 0)
			(effects
				(font
					(size 1.27 1.27)
					(thickness 0.15)
				)
				(justify left bottom)
				(hide yes)
			)
		)
		(property "Footprint" "antmicro-footprints:C_0402_1005Metric"
			(at 120.65 88.9 0)
			(effects
				(font
					(size 1.27 1.27)
					(thickness 0.15)
				)
				(justify left bottom)
				(hide yes)
			)
		)
		(property "Datasheet" "https://www.murata.com/products/productdetail?partno=GRM155R61H104KE14%23"
			(at 120.65 91.44 0)
			(effects
				(font
					(size 1.27 1.27)
					(thickness 0.15)
				)
				(justify left bottom)
				(hide yes)
			)
		)
		(property "Description" "SMD Multilayer Ceramic Capacitor, 0.1 µF, 50 V, 0402 [1005 Metric], ± 10%, X5R, GRM Series"
			(at 100.33 76.2 0)
			(effects
				(font
					(size 1.27 1.27)
				)
				(hide yes)
			)
		)
		(property "MPN" "GRM155R61H104KE14D"
			(at 120.65 93.98 0)
			(effects
				(font
					(size 1.27 1.27)
					(thickness 0.15)
				)
				(justify left bottom)
				(hide yes)
			)
		)
		(property "Manufacturer" "Murata"
			(at 120.65 96.52 0)
			(effects
				(font
					(size 1.27 1.27)
					(thickness 0.15)
				)
				(justify left bottom)
				(hide yes)
			)
		)
		(property "License" "Apache-2.0"
			(at 120.65 99.06 0)
			(effects
				(font
					(size 1.27 1.27)
					(thickness 0.15)
				)
				(justify left bottom)
				(hide yes)
			)
		)
		(property "Val" "100n"
			(at 99.695 77.47 0)
			(effects
				(font
					(size 1.27 1.27)
					(thickness 0.15)
				)
			)
		)
		(property "Voltage" "50V"
			(at 120.65 104.14 0)
			(effects
				(font
					(size 1.27 1.27)
				)
				(justify left bottom)
				(hide yes)
			)
		)
		(property "Dielectric" "X5R"
			(at 120.65 106.68 0)
			(effects
				(font
					(size 1.27 1.27)
				)
				(justify left bottom)
				(hide yes)
			)
		)
		(property "Author" "Antmicro"
			(at 120.65 101.6 0)
			(effects
				(font
					(size 1.27 1.27)
					(thickness 0.15)
				)
				(justify left bottom)
				(hide yes)
			)
		)
		(pin "1"
		)
		(pin "2"
		)
		(instances
			(project "thunderbolt-to-10gbe-adapter"
				(path ""
					(reference "C35")
					(unit 1)
				)
			)
		)
	)
	(symbol
		(lib_id "antmicroResistors0402:R_10k_0402")
		(at 336.55 85.09 90)
		(unit 1)
		(exclude_from_sim no)
		(in_bom yes)
		(on_board yes)
		(dnp no)
		(property "Reference" "R71"
			(at 337.82 81.28 90)
			(effects
				(font
					(size 1.27 1.27)
					(thickness 0.15)
				)
				(justify right)
			)
		)
		(property "Value" "R_10k_0402"
			(at 349.25 64.77 0)
			(effects
				(font
					(size 1.27 1.27)
					(thickness 0.15)
				)
				(justify left bottom)
				(hide yes)
			)
		)
		(property "Footprint" "antmicro-footprints:R_0402_1005Metric"
			(at 351.79 64.77 0)
			(effects
				(font
					(size 1.27 1.27)
					(thickness 0.15)
				)
				(justify left bottom)
				(hide yes)
			)
		)
		(property "Datasheet" "https://www.bourns.com/docs/product-datasheets/cr.pdf"
			(at 354.33 64.77 0)
			(effects
				(font
					(size 1.27 1.27)
					(thickness 0.15)
				)
				(justify left bottom)
				(hide yes)
			)
		)
		(property "Description" "SMD Chip Resistor, 10 kohm, ± 1%, 62.5 mW, 0402 [1005 Metric], Thick Film, General Purpose"
			(at 367.03 64.77 0)
			(effects
				(font
					(size 1.27 1.27)
				)
				(justify left bottom)
				(hide yes)
			)
		)
		(property "MPN" "CR0402-FX-1002GLF"
			(at 356.87 64.77 0)
			(effects
				(font
					(size 1.27 1.27)
					(thickness 0.15)
				)
				(justify left bottom)
				(hide yes)
			)
		)
		(property "Manufacturer" "Bourns"
			(at 359.41 64.77 0)
			(effects
				(font
					(size 1.27 1.27)
					(thickness 0.15)
				)
				(justify left bottom)
				(hide yes)
			)
		)
		(property "License" "Apache-2.0"
			(at 361.95 64.77 0)
			(effects
				(font
					(size 1.27 1.27)
					(thickness 0.15)
				)
				(justify left bottom)
				(hide yes)
			)
		)
		(property "Author" "Antmicro"
			(at 364.49 64.77 0)
			(effects
				(font
					(size 1.27 1.27)
					(thickness 0.15)
				)
				(justify left bottom)
				(hide yes)
			)
		)
		(property "Val" "10k"
			(at 337.82 83.82 90)
			(effects
				(font
					(size 1.27 1.27)
					(thickness 0.15)
				)
				(justify right)
			)
		)
		(property "Tolerance" "1%"
			(at 346.71 64.77 0)
			(effects
				(font
					(size 1.27 1.27)
				)
				(justify left bottom)
				(hide yes)
			)
		)
		(pin "2"
		)
		(pin "1"
		)
		(instances
			(project "thunderbolt-to-10gbe-adapter"
				(path ""
					(reference "R71")
					(unit 1)
				)
			)
		)
	)
	(symbol
		(lib_id "antmicropower:GND")
		(at 276.86 129.54 0)
		(unit 1)
		(exclude_from_sim no)
		(in_bom yes)
		(on_board yes)
		(dnp no)
		(property "Reference" "#PWR074"
			(at 276.86 135.89 0)
			(effects
				(font
					(size 1.27 1.27)
				)
				(hide yes)
			)
		)
		(property "Value" "GND"
			(at 276.86 133.35 0)
			(effects
				(font
					(size 1.27 1.27)
				)
			)
		)
		(property "Footprint" ""
			(at 276.86 129.54 0)
			(effects
				(font
					(size 1.27 1.27)
				)
				(hide yes)
			)
		)
		(property "Datasheet" ""
			(at 276.86 129.54 0)
			(effects
				(font
					(size 1.27 1.27)
				)
				(hide yes)
			)
		)
		(property "Description" ""
			(at 276.86 129.54 0)
			(effects
				(font
					(size 1.27 1.27)
				)
				(hide yes)
			)
		)
		(property "Author" "Antmicro"
			(at 285.75 137.16 0)
			(effects
				(font
					(size 1.27 1.27)
					(thickness 0.15)
				)
				(justify left bottom)
				(hide yes)
			)
		)
		(property "License" "Apache-2.0"
			(at 285.75 139.7 0)
			(effects
				(font
					(size 1.27 1.27)
					(thickness 0.15)
				)
				(justify left bottom)
				(hide yes)
			)
		)
		(pin "1"
		)
		(instances
			(project "thunderbolt-to-10gbe-adapter"
				(path ""
					(reference "#PWR074")
					(unit 1)
				)
			)
		)
	)
	(symbol
		(lib_id "antmicroResistors0402:R_10k_0402")
		(at 101.6 251.46 0)
		(unit 1)
		(exclude_from_sim no)
		(in_bom yes)
		(on_board yes)
		(dnp no)
		(property "Reference" "R51"
			(at 100.33 250.19 0)
			(effects
				(font
					(size 1.27 1.27)
					(thickness 0.15)
				)
			)
		)
		(property "Value" "R_10k_0402"
			(at 121.92 264.16 0)
			(effects
				(font
					(size 1.27 1.27)
					(thickness 0.15)
				)
				(justify left bottom)
				(hide yes)
			)
		)
		(property "Footprint" "antmicro-footprints:R_0402_1005Metric"
			(at 121.92 266.7 0)
			(effects
				(font
					(size 1.27 1.27)
					(thickness 0.15)
				)
				(justify left bottom)
				(hide yes)
			)
		)
		(property "Datasheet" "https://www.bourns.com/docs/product-datasheets/cr.pdf"
			(at 121.92 269.24 0)
			(effects
				(font
					(size 1.27 1.27)
					(thickness 0.15)
				)
				(justify left bottom)
				(hide yes)
			)
		)
		(property "Description" "SMD Chip Resistor, 10 kohm, ± 1%, 62.5 mW, 0402 [1005 Metric], Thick Film, General Purpose"
			(at 101.6 251.46 0)
			(effects
				(font
					(size 1.27 1.27)
				)
				(hide yes)
			)
		)
		(property "MPN" "CR0402-FX-1002GLF"
			(at 121.92 271.78 0)
			(effects
				(font
					(size 1.27 1.27)
					(thickness 0.15)
				)
				(justify left bottom)
				(hide yes)
			)
		)
		(property "Manufacturer" "Bourns"
			(at 121.92 274.32 0)
			(effects
				(font
					(size 1.27 1.27)
					(thickness 0.15)
				)
				(justify left bottom)
				(hide yes)
			)
		)
		(property "License" "Apache-2.0"
			(at 121.92 276.86 0)
			(effects
				(font
					(size 1.27 1.27)
					(thickness 0.15)
				)
				(justify left bottom)
				(hide yes)
			)
		)
		(property "Val" "10k"
			(at 107.95 250.19 0)
			(effects
				(font
					(size 1.27 1.27)
					(thickness 0.15)
				)
			)
		)
		(property "Tolerance" "1%"
			(at 121.92 261.62 0)
			(effects
				(font
					(size 1.27 1.27)
				)
				(justify left bottom)
				(hide yes)
			)
		)
		(property "Author" "Antmicro"
			(at 121.92 279.4 0)
			(effects
				(font
					(size 1.27 1.27)
					(thickness 0.15)
				)
				(justify left bottom)
				(hide yes)
			)
		)
		(pin "1"
		)
		(pin "2"
		)
		(instances
			(project "thunderbolt-to-10gbe-adapter"
				(path ""
					(reference "R51")
					(unit 1)
				)
			)
		)
	)
	(symbol
		(lib_id "antmicroResistors0402:R_10k_0402")
		(at 101.6 228.6 0)
		(unit 1)
		(exclude_from_sim no)
		(in_bom yes)
		(on_board yes)
		(dnp no)
		(property "Reference" "R45"
			(at 100.33 227.33 0)
			(effects
				(font
					(size 1.27 1.27)
					(thickness 0.15)
				)
			)
		)
		(property "Value" "R_10k_0402"
			(at 121.92 241.3 0)
			(effects
				(font
					(size 1.27 1.27)
					(thickness 0.15)
				)
				(justify left bottom)
				(hide yes)
			)
		)
		(property "Footprint" "antmicro-footprints:R_0402_1005Metric"
			(at 121.92 243.84 0)
			(effects
				(font
					(size 1.27 1.27)
					(thickness 0.15)
				)
				(justify left bottom)
				(hide yes)
			)
		)
		(property "Datasheet" "https://www.bourns.com/docs/product-datasheets/cr.pdf"
			(at 121.92 246.38 0)
			(effects
				(font
					(size 1.27 1.27)
					(thickness 0.15)
				)
				(justify left bottom)
				(hide yes)
			)
		)
		(property "Description" "SMD Chip Resistor, 10 kohm, ± 1%, 62.5 mW, 0402 [1005 Metric], Thick Film, General Purpose"
			(at 101.6 228.6 0)
			(effects
				(font
					(size 1.27 1.27)
				)
				(hide yes)
			)
		)
		(property "MPN" "CR0402-FX-1002GLF"
			(at 121.92 248.92 0)
			(effects
				(font
					(size 1.27 1.27)
					(thickness 0.15)
				)
				(justify left bottom)
				(hide yes)
			)
		)
		(property "Manufacturer" "Bourns"
			(at 121.92 251.46 0)
			(effects
				(font
					(size 1.27 1.27)
					(thickness 0.15)
				)
				(justify left bottom)
				(hide yes)
			)
		)
		(property "License" "Apache-2.0"
			(at 121.92 254 0)
			(effects
				(font
					(size 1.27 1.27)
					(thickness 0.15)
				)
				(justify left bottom)
				(hide yes)
			)
		)
		(property "Val" "10k"
			(at 107.95 227.33 0)
			(effects
				(font
					(size 1.27 1.27)
					(thickness 0.15)
				)
			)
		)
		(property "Tolerance" "1%"
			(at 121.92 238.76 0)
			(effects
				(font
					(size 1.27 1.27)
				)
				(justify left bottom)
				(hide yes)
			)
		)
		(property "Author" "Antmicro"
			(at 121.92 256.54 0)
			(effects
				(font
					(size 1.27 1.27)
					(thickness 0.15)
				)
				(justify left bottom)
				(hide yes)
			)
		)
		(pin "1"
		)
		(pin "2"
		)
		(instances
			(project "thunderbolt-to-10gbe-adapter"
				(path ""
					(reference "R45")
					(unit 1)
				)
			)
		)
	)
	(symbol
		(lib_id "antmicroResistors0402:R_100k_0402")
		(at 101.6 203.2 0)
		(unit 1)
		(exclude_from_sim no)
		(in_bom yes)
		(on_board yes)
		(dnp no)
		(fields_autoplaced yes)
		(property "Reference" "R41"
			(at 104.14 196.85 0)
			(effects
				(font
					(size 1.27 1.27)
					(thickness 0.15)
				)
			)
		)
		(property "Value" "R_100k_0402"
			(at 121.92 215.9 0)
			(effects
				(font
					(size 1.27 1.27)
					(thickness 0.15)
				)
				(justify left bottom)
				(hide yes)
			)
		)
		(property "Footprint" "antmicro-footprints:R_0402_1005Metric"
			(at 121.92 218.44 0)
			(effects
				(font
					(size 1.27 1.27)
					(thickness 0.15)
				)
				(justify left bottom)
				(hide yes)
			)
		)
		(property "Datasheet" "https://www.bourns.com/docs/product-datasheets/cr.pdf"
			(at 121.92 220.98 0)
			(effects
				(font
					(size 1.27 1.27)
					(thickness 0.15)
				)
				(justify left bottom)
				(hide yes)
			)
		)
		(property "Description" "SMD Chip Resistor, 100 kohm, ± 1%, 62.5 mW, 0402 [1005 Metric], Thick Film, General Purpose"
			(at 101.6 203.2 0)
			(effects
				(font
					(size 1.27 1.27)
				)
				(hide yes)
			)
		)
		(property "MPN" "CR0402-FX-1003GLF"
			(at 121.92 223.52 0)
			(effects
				(font
					(size 1.27 1.27)
					(thickness 0.15)
				)
				(justify left bottom)
				(hide yes)
			)
		)
		(property "Manufacturer" "Bourns"
			(at 121.92 226.06 0)
			(effects
				(font
					(size 1.27 1.27)
					(thickness 0.15)
				)
				(justify left bottom)
				(hide yes)
			)
		)
		(property "License" "Apache-2.0"
			(at 121.92 228.6 0)
			(effects
				(font
					(size 1.27 1.27)
					(thickness 0.15)
				)
				(justify left bottom)
				(hide yes)
			)
		)
		(property "Val" "100k"
			(at 104.14 199.39 0)
			(effects
				(font
					(size 1.27 1.27)
					(thickness 0.15)
				)
			)
		)
		(property "Tolerance" "1%"
			(at 121.92 213.36 0)
			(effects
				(font
					(size 1.27 1.27)
				)
				(justify left bottom)
				(hide yes)
			)
		)
		(property "Author" "Antmicro"
			(at 121.92 231.14 0)
			(effects
				(font
					(size 1.27 1.27)
					(thickness 0.15)
				)
				(justify left bottom)
				(hide yes)
			)
		)
		(pin "1"
		)
		(pin "2"
		)
		(instances
			(project "thunderbolt-to-10gbe-adapter"
				(path ""
					(reference "R41")
					(unit 1)
				)
			)
		)
	)
	(symbol
		(lib_id "antmicroResistors0402:R_10k_0402")
		(at 254 85.09 0)
		(unit 1)
		(exclude_from_sim no)
		(in_bom yes)
		(on_board yes)
		(dnp no)
		(fields_autoplaced yes)
		(property "Reference" "R67"
			(at 256.54 88.9 0)
			(effects
				(font
					(size 1.27 1.27)
					(thickness 0.15)
				)
			)
		)
		(property "Value" "R_10k_0402"
			(at 274.32 97.79 0)
			(effects
				(font
					(size 1.27 1.27)
					(thickness 0.15)
				)
				(justify left bottom)
				(hide yes)
			)
		)
		(property "Footprint" "antmicro-footprints:R_0402_1005Metric"
			(at 274.32 100.33 0)
			(effects
				(font
					(size 1.27 1.27)
					(thickness 0.15)
				)
				(justify left bottom)
				(hide yes)
			)
		)
		(property "Datasheet" "https://www.bourns.com/docs/product-datasheets/cr.pdf"
			(at 274.32 102.87 0)
			(effects
				(font
					(size 1.27 1.27)
					(thickness 0.15)
				)
				(justify left bottom)
				(hide yes)
			)
		)
		(property "Description" "SMD Chip Resistor, 10 kohm, ± 1%, 62.5 mW, 0402 [1005 Metric], Thick Film, General Purpose"
			(at 254 85.09 0)
			(effects
				(font
					(size 1.27 1.27)
				)
				(hide yes)
			)
		)
		(property "MPN" "CR0402-FX-1002GLF"
			(at 274.32 105.41 0)
			(effects
				(font
					(size 1.27 1.27)
					(thickness 0.15)
				)
				(justify left bottom)
				(hide yes)
			)
		)
		(property "Manufacturer" "Bourns"
			(at 274.32 107.95 0)
			(effects
				(font
					(size 1.27 1.27)
					(thickness 0.15)
				)
				(justify left bottom)
				(hide yes)
			)
		)
		(property "License" "Apache-2.0"
			(at 274.32 110.49 0)
			(effects
				(font
					(size 1.27 1.27)
					(thickness 0.15)
				)
				(justify left bottom)
				(hide yes)
			)
		)
		(property "Val" "10k"
			(at 256.54 91.44 0)
			(effects
				(font
					(size 1.27 1.27)
					(thickness 0.15)
				)
			)
		)
		(property "Tolerance" "1%"
			(at 274.32 95.25 0)
			(effects
				(font
					(size 1.27 1.27)
				)
				(justify left bottom)
				(hide yes)
			)
		)
		(property "Author" "Antmicro"
			(at 274.32 113.03 0)
			(effects
				(font
					(size 1.27 1.27)
					(thickness 0.15)
				)
				(justify left bottom)
				(hide yes)
			)
		)
		(pin "1"
		)
		(pin "2"
		)
		(instances
			(project "thunderbolt-to-10gbe-adapter"
				(path ""
					(reference "R67")
					(unit 1)
				)
			)
		)
	)
	(symbol
		(lib_id "antmicroResistors0402:R_100k_0402")
		(at 33.02 256.54 0)
		(unit 1)
		(exclude_from_sim no)
		(in_bom yes)
		(on_board yes)
		(dnp no)
		(fields_autoplaced yes)
		(property "Reference" "R37"
			(at 35.56 250.19 0)
			(effects
				(font
					(size 1.27 1.27)
					(thickness 0.15)
				)
			)
		)
		(property "Value" "R_100k_0402"
			(at 53.34 269.24 0)
			(effects
				(font
					(size 1.27 1.27)
					(thickness 0.15)
				)
				(justify left bottom)
				(hide yes)
			)
		)
		(property "Footprint" "antmicro-footprints:R_0402_1005Metric"
			(at 53.34 271.78 0)
			(effects
				(font
					(size 1.27 1.27)
					(thickness 0.15)
				)
				(justify left bottom)
				(hide yes)
			)
		)
		(property "Datasheet" "https://www.bourns.com/docs/product-datasheets/cr.pdf"
			(at 53.34 274.32 0)
			(effects
				(font
					(size 1.27 1.27)
					(thickness 0.15)
				)
				(justify left bottom)
				(hide yes)
			)
		)
		(property "Description" "SMD Chip Resistor, 100 kohm, ± 1%, 62.5 mW, 0402 [1005 Metric], Thick Film, General Purpose"
			(at 33.02 256.54 0)
			(effects
				(font
					(size 1.27 1.27)
				)
				(hide yes)
			)
		)
		(property "MPN" "CR0402-FX-1003GLF"
			(at 53.34 276.86 0)
			(effects
				(font
					(size 1.27 1.27)
					(thickness 0.15)
				)
				(justify left bottom)
				(hide yes)
			)
		)
		(property "Manufacturer" "Bourns"
			(at 53.34 279.4 0)
			(effects
				(font
					(size 1.27 1.27)
					(thickness 0.15)
				)
				(justify left bottom)
				(hide yes)
			)
		)
		(property "License" "Apache-2.0"
			(at 53.34 281.94 0)
			(effects
				(font
					(size 1.27 1.27)
					(thickness 0.15)
				)
				(justify left bottom)
				(hide yes)
			)
		)
		(property "Val" "100k"
			(at 35.56 252.73 0)
			(effects
				(font
					(size 1.27 1.27)
					(thickness 0.15)
				)
			)
		)
		(property "Tolerance" "1%"
			(at 53.34 266.7 0)
			(effects
				(font
					(size 1.27 1.27)
				)
				(justify left bottom)
				(hide yes)
			)
		)
		(property "Author" "Antmicro"
			(at 53.34 284.48 0)
			(effects
				(font
					(size 1.27 1.27)
					(thickness 0.15)
				)
				(justify left bottom)
				(hide yes)
			)
		)
		(pin "1"
		)
		(pin "2"
		)
		(instances
			(project "thunderbolt-to-10gbe-adapter"
				(path ""
					(reference "R37")
					(unit 1)
				)
			)
		)
	)
	(symbol
		(lib_id "antmicropower:+3V3")
		(at 177.8 181.61 0)
		(unit 1)
		(exclude_from_sim no)
		(in_bom yes)
		(on_board yes)
		(dnp no)
		(property "Reference" "#PWR067"
			(at 193.04 181.61 0)
			(effects
				(font
					(size 1.27 1.27)
					(thickness 0.15)
				)
				(justify left bottom)
				(hide yes)
			)
		)
		(property "Value" "+3V3_TB"
			(at 177.8 177.8 0)
			(effects
				(font
					(size 1.27 1.27)
					(thickness 0.15)
				)
			)
		)
		(property "Footprint" ""
			(at 193.04 189.23 0)
			(effects
				(font
					(size 1.27 1.27)
					(thickness 0.15)
				)
				(justify left bottom)
				(hide yes)
			)
		)
		(property "Datasheet" ""
			(at 193.04 191.77 0)
			(effects
				(font
					(size 1.27 1.27)
					(thickness 0.15)
				)
				(justify left bottom)
				(hide yes)
			)
		)
		(property "Description" ""
			(at 193.04 194.31 0)
			(effects
				(font
					(size 1.27 1.27)
				)
				(justify left bottom)
				(hide yes)
			)
		)
		(property "Author" "Antmicro"
			(at 193.04 184.15 0)
			(effects
				(font
					(size 1.27 1.27)
					(thickness 0.15)
				)
				(justify left bottom)
				(hide yes)
			)
		)
		(property "License" "Apache-2.0"
			(at 193.04 186.69 0)
			(effects
				(font
					(size 1.27 1.27)
					(thickness 0.15)
				)
				(justify left bottom)
				(hide yes)
			)
		)
		(pin "1"
		)
		(instances
			(project "thunderbolt-to-10gbe-adapter"
				(path ""
					(reference "#PWR067")
					(unit 1)
				)
			)
		)
	)
	(symbol
		(lib_id "antmicroCapacitors0402:C_100n_0402")
		(at 105.41 78.74 0)
		(unit 1)
		(exclude_from_sim no)
		(in_bom yes)
		(on_board yes)
		(dnp no)
		(property "Reference" "C38"
			(at 111.125 77.47 0)
			(effects
				(font
					(size 1.27 1.27)
					(thickness 0.15)
				)
			)
		)
		(property "Value" "C_100n_0402"
			(at 125.73 88.9 0)
			(effects
				(font
					(size 1.27 1.27)
					(thickness 0.15)
				)
				(justify left bottom)
				(hide yes)
			)
		)
		(property "Footprint" "antmicro-footprints:C_0402_1005Metric"
			(at 125.73 91.44 0)
			(effects
				(font
					(size 1.27 1.27)
					(thickness 0.15)
				)
				(justify left bottom)
				(hide yes)
			)
		)
		(property "Datasheet" "https://www.murata.com/products/productdetail?partno=GRM155R61H104KE14%23"
			(at 125.73 93.98 0)
			(effects
				(font
					(size 1.27 1.27)
					(thickness 0.15)
				)
				(justify left bottom)
				(hide yes)
			)
		)
		(property "Description" "SMD Multilayer Ceramic Capacitor, 0.1 µF, 50 V, 0402 [1005 Metric], ± 10%, X5R, GRM Series"
			(at 105.41 78.74 0)
			(effects
				(font
					(size 1.27 1.27)
				)
				(hide yes)
			)
		)
		(property "MPN" "GRM155R61H104KE14D"
			(at 125.73 96.52 0)
			(effects
				(font
					(size 1.27 1.27)
					(thickness 0.15)
				)
				(justify left bottom)
				(hide yes)
			)
		)
		(property "Manufacturer" "Murata"
			(at 125.73 99.06 0)
			(effects
				(font
					(size 1.27 1.27)
					(thickness 0.15)
				)
				(justify left bottom)
				(hide yes)
			)
		)
		(property "License" "Apache-2.0"
			(at 125.73 101.6 0)
			(effects
				(font
					(size 1.27 1.27)
					(thickness 0.15)
				)
				(justify left bottom)
				(hide yes)
			)
		)
		(property "Val" "100n"
			(at 111.125 80.01 0)
			(effects
				(font
					(size 1.27 1.27)
					(thickness 0.15)
				)
			)
		)
		(property "Voltage" "50V"
			(at 125.73 106.68 0)
			(effects
				(font
					(size 1.27 1.27)
				)
				(justify left bottom)
				(hide yes)
			)
		)
		(property "Dielectric" "X5R"
			(at 125.73 109.22 0)
			(effects
				(font
					(size 1.27 1.27)
				)
				(justify left bottom)
				(hide yes)
			)
		)
		(property "Author" "Antmicro"
			(at 125.73 104.14 0)
			(effects
				(font
					(size 1.27 1.27)
					(thickness 0.15)
				)
				(justify left bottom)
				(hide yes)
			)
		)
		(pin "1"
		)
		(pin "2"
		)
		(instances
			(project "thunderbolt-to-10gbe-adapter"
				(path ""
					(reference "C38")
					(unit 1)
				)
			)
		)
	)
	(symbol
		(lib_id "antmicroResistors0402:R_100R_0402")
		(at 257.81 186.69 0)
		(unit 1)
		(exclude_from_sim no)
		(in_bom yes)
		(on_board yes)
		(dnp no)
		(property "Reference" "R69"
			(at 256.54 185.42 0)
			(effects
				(font
					(size 1.27 1.27)
					(thickness 0.15)
				)
			)
		)
		(property "Value" "R_100R_0402"
			(at 278.13 199.39 0)
			(effects
				(font
					(size 1.27 1.27)
					(thickness 0.15)
				)
				(justify left bottom)
				(hide yes)
			)
		)
		(property "Footprint" "antmicro-footprints:R_0402_1005Metric"
			(at 278.13 201.93 0)
			(effects
				(font
					(size 1.27 1.27)
					(thickness 0.15)
				)
				(justify left bottom)
				(hide yes)
			)
		)
		(property "Datasheet" "https://www.bourns.com/docs/product-datasheets/cr.pdf"
			(at 278.13 204.47 0)
			(effects
				(font
					(size 1.27 1.27)
					(thickness 0.15)
				)
				(justify left bottom)
				(hide yes)
			)
		)
		(property "Description" "SMD Chip Resistor, 100 ohm, ± 1%, 62.5 mW, 0402 [1005 Metric], Thick Film, General Purpose"
			(at 257.81 186.69 0)
			(effects
				(font
					(size 1.27 1.27)
				)
				(hide yes)
			)
		)
		(property "MPN" "CR0402-FX-1000GLF"
			(at 278.13 207.01 0)
			(effects
				(font
					(size 1.27 1.27)
					(thickness 0.15)
				)
				(justify left bottom)
				(hide yes)
			)
		)
		(property "Manufacturer" "Bourns"
			(at 278.13 209.55 0)
			(effects
				(font
					(size 1.27 1.27)
					(thickness 0.15)
				)
				(justify left bottom)
				(hide yes)
			)
		)
		(property "License" "Apache-2.0"
			(at 278.13 212.09 0)
			(effects
				(font
					(size 1.27 1.27)
					(thickness 0.15)
				)
				(justify left bottom)
				(hide yes)
			)
		)
		(property "Val" "100R"
			(at 264.795 185.42 0)
			(effects
				(font
					(size 1.27 1.27)
					(thickness 0.15)
				)
			)
		)
		(property "Tolerance" "1%"
			(at 278.13 196.85 0)
			(effects
				(font
					(size 1.27 1.27)
				)
				(justify left bottom)
				(hide yes)
			)
		)
		(property "Author" "Antmicro"
			(at 278.13 214.63 0)
			(effects
				(font
					(size 1.27 1.27)
					(thickness 0.15)
				)
				(justify left bottom)
				(hide yes)
			)
		)
		(pin "1"
		)
		(pin "2"
		)
		(instances
			(project "thunderbolt-to-10gbe-adapter"
				(path ""
					(reference "R69")
					(unit 1)
				)
			)
		)
	)
	(symbol
		(lib_id "antmicroResistors0402:R_100k_0402")
		(at 127 252.73 90)
		(unit 1)
		(exclude_from_sim no)
		(in_bom yes)
		(on_board yes)
		(dnp no)
		(fields_autoplaced yes)
		(property "Reference" "R57"
			(at 128.905 248.92 90)
			(effects
				(font
					(size 1.27 1.27)
					(thickness 0.15)
				)
				(justify right)
			)
		)
		(property "Value" "R_100k_0402"
			(at 139.7 232.41 0)
			(effects
				(font
					(size 1.27 1.27)
					(thickness 0.15)
				)
				(justify left bottom)
				(hide yes)
			)
		)
		(property "Footprint" "antmicro-footprints:R_0402_1005Metric"
			(at 142.24 232.41 0)
			(effects
				(font
					(size 1.27 1.27)
					(thickness 0.15)
				)
				(justify left bottom)
				(hide yes)
			)
		)
		(property "Datasheet" "https://www.bourns.com/docs/product-datasheets/cr.pdf"
			(at 144.78 232.41 0)
			(effects
				(font
					(size 1.27 1.27)
					(thickness 0.15)
				)
				(justify left bottom)
				(hide yes)
			)
		)
		(property "Description" "SMD Chip Resistor, 100 kohm, ± 1%, 62.5 mW, 0402 [1005 Metric], Thick Film, General Purpose"
			(at 127 252.73 0)
			(effects
				(font
					(size 1.27 1.27)
				)
				(hide yes)
			)
		)
		(property "MPN" "CR0402-FX-1003GLF"
			(at 147.32 232.41 0)
			(effects
				(font
					(size 1.27 1.27)
					(thickness 0.15)
				)
				(justify left bottom)
				(hide yes)
			)
		)
		(property "Manufacturer" "Bourns"
			(at 149.86 232.41 0)
			(effects
				(font
					(size 1.27 1.27)
					(thickness 0.15)
				)
				(justify left bottom)
				(hide yes)
			)
		)
		(property "License" "Apache-2.0"
			(at 152.4 232.41 0)
			(effects
				(font
					(size 1.27 1.27)
					(thickness 0.15)
				)
				(justify left bottom)
				(hide yes)
			)
		)
		(property "Val" "100k"
			(at 128.905 251.46 90)
			(effects
				(font
					(size 1.27 1.27)
					(thickness 0.15)
				)
				(justify right)
			)
		)
		(property "Tolerance" "1%"
			(at 137.16 232.41 0)
			(effects
				(font
					(size 1.27 1.27)
				)
				(justify left bottom)
				(hide yes)
			)
		)
		(property "Author" "Antmicro"
			(at 154.94 232.41 0)
			(effects
				(font
					(size 1.27 1.27)
					(thickness 0.15)
				)
				(justify left bottom)
				(hide yes)
			)
		)
		(pin "1"
		)
		(pin "2"
		)
		(instances
			(project "thunderbolt-to-10gbe-adapter"
				(path ""
					(reference "R57")
					(unit 1)
				)
			)
		)
	)
	(symbol
		(lib_id "antmicroCapacitors0402:C_220n_0402")
		(at 341.63 48.26 0)
		(unit 1)
		(exclude_from_sim no)
		(in_bom yes)
		(on_board yes)
		(dnp no)
		(property "Reference" "C48"
			(at 340.868 49.53 0)
			(effects
				(font
					(size 1.27 1.27)
					(thickness 0.15)
				)
			)
		)
		(property "Value" "C_220n_0402"
			(at 361.95 58.42 0)
			(effects
				(font
					(size 1.27 1.27)
					(thickness 0.15)
				)
				(justify left bottom)
				(hide yes)
			)
		)
		(property "Footprint" "antmicro-footprints:C_0402_1005Metric"
			(at 361.95 60.96 0)
			(effects
				(font
					(size 1.27 1.27)
					(thickness 0.15)
				)
				(justify left bottom)
				(hide yes)
			)
		)
		(property "Datasheet" "https://www.yageo.com/en/Chart/Download/pdf/CC0402KRX5R6BB224"
			(at 361.95 63.5 0)
			(effects
				(font
					(size 1.27 1.27)
					(thickness 0.15)
				)
				(justify left bottom)
				(hide yes)
			)
		)
		(property "Description" "SMD Multilayer Ceramic Capacitor, 0.22 µF, 10 V, 0402 [1005 Metric], ± 10%, X5R, CC Series"
			(at 341.63 48.26 0)
			(effects
				(font
					(size 1.27 1.27)
				)
				(hide yes)
			)
		)
		(property "MPN" "CC0402KRX5R6BB224"
			(at 361.95 66.04 0)
			(effects
				(font
					(size 1.27 1.27)
					(thickness 0.15)
				)
				(justify left bottom)
				(hide yes)
			)
		)
		(property "Manufacturer" "YAGEO"
			(at 361.95 68.58 0)
			(effects
				(font
					(size 1.27 1.27)
					(thickness 0.15)
				)
				(justify left bottom)
				(hide yes)
			)
		)
		(property "License" "Apache-2.0"
			(at 361.95 71.12 0)
			(effects
				(font
					(size 1.27 1.27)
					(thickness 0.15)
				)
				(justify left bottom)
				(hide yes)
			)
		)
		(property "Val" "220n"
			(at 347.472 49.53 0)
			(effects
				(font
					(size 1.27 1.27)
					(thickness 0.15)
				)
			)
		)
		(property "Voltage" ""
			(at 361.95 76.2 0)
			(effects
				(font
					(size 1.27 1.27)
				)
				(justify left bottom)
				(hide yes)
			)
		)
		(property "Dielectric" ""
			(at 361.95 78.74 0)
			(effects
				(font
					(size 1.27 1.27)
				)
				(justify left bottom)
				(hide yes)
			)
		)
		(property "Author" "Antmicro"
			(at 361.95 73.66 0)
			(effects
				(font
					(size 1.27 1.27)
					(thickness 0.15)
				)
				(justify left bottom)
				(hide yes)
			)
		)
		(pin "1"
		)
		(pin "2"
		)
		(instances
			(project "thunderbolt-to-10gbe-adapter"
				(path ""
					(reference "C48")
					(unit 1)
				)
			)
		)
	)
	(symbol
		(lib_id "antmicroResistors0402:R_3k01_0402")
		(at 322.58 83.82 0)
		(unit 1)
		(exclude_from_sim no)
		(in_bom yes)
		(on_board yes)
		(dnp no)
		(fields_autoplaced yes)
		(property "Reference" "R70"
			(at 325.12 87.63 0)
			(effects
				(font
					(size 1.27 1.27)
					(thickness 0.15)
				)
			)
		)
		(property "Value" "R_3k01_0402"
			(at 342.9 96.52 0)
			(effects
				(font
					(size 1.27 1.27)
					(thickness 0.15)
				)
				(justify left bottom)
				(hide yes)
			)
		)
		(property "Footprint" "antmicro-footprints:R_0402_1005Metric"
			(at 342.9 99.06 0)
			(effects
				(font
					(size 1.27 1.27)
					(thickness 0.15)
				)
				(justify left bottom)
				(hide yes)
			)
		)
		(property "Datasheet" "https://www.bourns.com/docs/product-datasheets/cr.pdf"
			(at 342.9 101.6 0)
			(effects
				(font
					(size 1.27 1.27)
					(thickness 0.15)
				)
				(justify left bottom)
				(hide yes)
			)
		)
		(property "Description" "SMD Chip Resistor, 3.01 kohm, ± 1%, 62.5 mW, 0402 [1005 Metric], Thick Film, General Purpose"
			(at 322.58 83.82 0)
			(effects
				(font
					(size 1.27 1.27)
				)
				(hide yes)
			)
		)
		(property "MPN" "CR0402-FX-3011GLF"
			(at 342.9 104.14 0)
			(effects
				(font
					(size 1.27 1.27)
					(thickness 0.15)
				)
				(justify left bottom)
				(hide yes)
			)
		)
		(property "Manufacturer" "Bourns"
			(at 342.9 106.68 0)
			(effects
				(font
					(size 1.27 1.27)
					(thickness 0.15)
				)
				(justify left bottom)
				(hide yes)
			)
		)
		(property "License" "Apache-2.0"
			(at 342.9 109.22 0)
			(effects
				(font
					(size 1.27 1.27)
					(thickness 0.15)
				)
				(justify left bottom)
				(hide yes)
			)
		)
		(property "Val" "3k01"
			(at 325.12 90.17 0)
			(effects
				(font
					(size 1.27 1.27)
					(thickness 0.15)
				)
			)
		)
		(property "Tolerance" "1%"
			(at 342.9 93.98 0)
			(effects
				(font
					(size 1.27 1.27)
				)
				(justify left bottom)
				(hide yes)
			)
		)
		(property "Author" "Antmicro"
			(at 342.9 111.76 0)
			(effects
				(font
					(size 1.27 1.27)
					(thickness 0.15)
				)
				(justify left bottom)
				(hide yes)
			)
		)
		(pin "1"
		)
		(pin "2"
		)
		(instances
			(project "thunderbolt-to-10gbe-adapter"
				(path ""
					(reference "R70")
					(unit 1)
				)
			)
		)
	)
	(symbol
		(lib_id "antmicroCapacitors0402:C_220n_0402")
		(at 105.41 71.12 0)
		(unit 1)
		(exclude_from_sim no)
		(in_bom yes)
		(on_board yes)
		(dnp no)
		(property "Reference" "C37"
			(at 111.125 69.85 0)
			(effects
				(font
					(size 1.27 1.27)
					(thickness 0.15)
				)
			)
		)
		(property "Value" "C_220n_0402"
			(at 125.73 81.28 0)
			(effects
				(font
					(size 1.27 1.27)
					(thickness 0.15)
				)
				(justify left bottom)
				(hide yes)
			)
		)
		(property "Footprint" "antmicro-footprints:C_0402_1005Metric"
			(at 125.73 83.82 0)
			(effects
				(font
					(size 1.27 1.27)
					(thickness 0.15)
				)
				(justify left bottom)
				(hide yes)
			)
		)
		(property "Datasheet" "https://www.yageo.com/en/Chart/Download/pdf/CC0402KRX5R6BB224"
			(at 125.73 86.36 0)
			(effects
				(font
					(size 1.27 1.27)
					(thickness 0.15)
				)
				(justify left bottom)
				(hide yes)
			)
		)
		(property "Description" "SMD Multilayer Ceramic Capacitor, 0.22 µF, 10 V, 0402 [1005 Metric], ± 10%, X5R, CC Series"
			(at 105.41 71.12 0)
			(effects
				(font
					(size 1.27 1.27)
				)
				(hide yes)
			)
		)
		(property "MPN" "CC0402KRX5R6BB224"
			(at 125.73 88.9 0)
			(effects
				(font
					(size 1.27 1.27)
					(thickness 0.15)
				)
				(justify left bottom)
				(hide yes)
			)
		)
		(property "Manufacturer" "YAGEO"
			(at 125.73 91.44 0)
			(effects
				(font
					(size 1.27 1.27)
					(thickness 0.15)
				)
				(justify left bottom)
				(hide yes)
			)
		)
		(property "License" "Apache-2.0"
			(at 125.73 93.98 0)
			(effects
				(font
					(size 1.27 1.27)
					(thickness 0.15)
				)
				(justify left bottom)
				(hide yes)
			)
		)
		(property "Val" "220n"
			(at 111.125 72.39 0)
			(effects
				(font
					(size 1.27 1.27)
					(thickness 0.15)
				)
			)
		)
		(property "Voltage" ""
			(at 125.73 99.06 0)
			(effects
				(font
					(size 1.27 1.27)
				)
				(justify left bottom)
				(hide yes)
			)
		)
		(property "Dielectric" ""
			(at 125.73 101.6 0)
			(effects
				(font
					(size 1.27 1.27)
				)
				(justify left bottom)
				(hide yes)
			)
		)
		(property "Author" "Antmicro"
			(at 125.73 96.52 0)
			(effects
				(font
					(size 1.27 1.27)
					(thickness 0.15)
				)
				(justify left bottom)
				(hide yes)
			)
		)
		(pin "1"
		)
		(pin "2"
		)
		(instances
			(project "thunderbolt-to-10gbe-adapter"
				(path ""
					(reference "C37")
					(unit 1)
				)
			)
		)
	)
	(symbol
		(lib_id "antmicropower:GND")
		(at 113.03 260.35 0)
		(unit 1)
		(exclude_from_sim no)
		(in_bom yes)
		(on_board yes)
		(dnp no)
		(property "Reference" "#PWR064"
			(at 113.03 266.7 0)
			(effects
				(font
					(size 1.27 1.27)
				)
				(hide yes)
			)
		)
		(property "Value" "GND"
			(at 113.03 264.16 0)
			(effects
				(font
					(size 1.27 1.27)
				)
			)
		)
		(property "Footprint" ""
			(at 113.03 260.35 0)
			(effects
				(font
					(size 1.27 1.27)
				)
				(hide yes)
			)
		)
		(property "Datasheet" ""
			(at 113.03 260.35 0)
			(effects
				(font
					(size 1.27 1.27)
				)
				(hide yes)
			)
		)
		(property "Description" ""
			(at 113.03 260.35 0)
			(effects
				(font
					(size 1.27 1.27)
				)
				(hide yes)
			)
		)
		(property "Author" "Antmicro"
			(at 121.92 267.97 0)
			(effects
				(font
					(size 1.27 1.27)
					(thickness 0.15)
				)
				(justify left bottom)
				(hide yes)
			)
		)
		(property "License" "Apache-2.0"
			(at 121.92 270.51 0)
			(effects
				(font
					(size 1.27 1.27)
					(thickness 0.15)
				)
				(justify left bottom)
				(hide yes)
			)
		)
		(pin "1"
		)
		(instances
			(project "thunderbolt-to-10gbe-adapter"
				(path ""
					(reference "#PWR064")
					(unit 1)
				)
			)
		)
	)
	(symbol
		(lib_id "antmicropower:GND")
		(at 30.48 212.09 0)
		(mirror y)
		(unit 1)
		(exclude_from_sim no)
		(in_bom yes)
		(on_board yes)
		(dnp no)
		(property "Reference" "#PWR058"
			(at 30.48 218.44 0)
			(effects
				(font
					(size 1.27 1.27)
				)
				(hide yes)
			)
		)
		(property "Value" "GND"
			(at 30.48 215.9 0)
			(effects
				(font
					(size 1.27 1.27)
				)
			)
		)
		(property "Footprint" ""
			(at 30.48 212.09 0)
			(effects
				(font
					(size 1.27 1.27)
				)
				(hide yes)
			)
		)
		(property "Datasheet" ""
			(at 30.48 212.09 0)
			(effects
				(font
					(size 1.27 1.27)
				)
				(hide yes)
			)
		)
		(property "Description" ""
			(at 30.48 212.09 0)
			(effects
				(font
					(size 1.27 1.27)
				)
				(hide yes)
			)
		)
		(property "Author" "Antmicro"
			(at 21.59 219.71 0)
			(effects
				(font
					(size 1.27 1.27)
					(thickness 0.15)
				)
				(justify left bottom)
				(hide yes)
			)
		)
		(property "License" "Apache-2.0"
			(at 21.59 222.25 0)
			(effects
				(font
					(size 1.27 1.27)
					(thickness 0.15)
				)
				(justify left bottom)
				(hide yes)
			)
		)
		(pin "1"
		)
		(instances
			(project "thunderbolt-to-10gbe-adapter"
				(path ""
					(reference "#PWR058")
					(unit 1)
				)
			)
		)
	)
	(symbol
		(lib_id "antmicroResistors0402:R_2k2_0402")
		(at 33.02 261.62 0)
		(unit 1)
		(exclude_from_sim no)
		(in_bom yes)
		(on_board yes)
		(dnp no)
		(property "Reference" "R38"
			(at 35.56 259.715 0)
			(effects
				(font
					(size 1.27 1.27)
					(thickness 0.15)
				)
			)
		)
		(property "Value" "R_2k2_0402"
			(at 53.34 274.32 0)
			(effects
				(font
					(size 1.27 1.27)
					(thickness 0.15)
				)
				(justify left bottom)
				(hide yes)
			)
		)
		(property "Footprint" "antmicro-footprints:R_0402_1005Metric"
			(at 53.34 276.86 0)
			(effects
				(font
					(size 1.27 1.27)
					(thickness 0.15)
				)
				(justify left bottom)
				(hide yes)
			)
		)
		(property "Datasheet" "https://www.bourns.com/docs/product-datasheets/cr.pdf"
			(at 53.34 279.4 0)
			(effects
				(font
					(size 1.27 1.27)
					(thickness 0.15)
				)
				(justify left bottom)
				(hide yes)
			)
		)
		(property "Description" "SMD Chip Resistor, 2.2 kohm, ± 1%, 62.5 mW, 0402 [1005 Metric], Thick Film, General Purpose"
			(at 33.02 261.62 0)
			(effects
				(font
					(size 1.27 1.27)
				)
				(hide yes)
			)
		)
		(property "MPN" "CR0402-FX-2201GLF"
			(at 53.34 281.94 0)
			(effects
				(font
					(size 1.27 1.27)
					(thickness 0.15)
				)
				(justify left bottom)
				(hide yes)
			)
		)
		(property "Manufacturer" "Bourns"
			(at 53.34 284.48 0)
			(effects
				(font
					(size 1.27 1.27)
					(thickness 0.15)
				)
				(justify left bottom)
				(hide yes)
			)
		)
		(property "License" "Apache-2.0"
			(at 53.34 287.02 0)
			(effects
				(font
					(size 1.27 1.27)
					(thickness 0.15)
				)
				(justify left bottom)
				(hide yes)
			)
		)
		(property "Val" "2k2"
			(at 39.37 260.35 0)
			(effects
				(font
					(size 1.27 1.27)
					(thickness 0.15)
				)
			)
		)
		(property "Tolerance" "1%"
			(at 53.34 271.78 0)
			(effects
				(font
					(size 1.27 1.27)
				)
				(justify left bottom)
				(hide yes)
			)
		)
		(property "Author" "Antmicro"
			(at 53.34 289.56 0)
			(effects
				(font
					(size 1.27 1.27)
					(thickness 0.15)
				)
				(justify left bottom)
				(hide yes)
			)
		)
		(pin "1"
		)
		(pin "2"
		)
		(instances
			(project "thunderbolt-to-10gbe-adapter"
				(path ""
					(reference "R38")
					(unit 1)
				)
			)
		)
	)
	(symbol
		(lib_id "antmicroResistors0402:R_2k2_0402")
		(at 33.02 210.82 0)
		(unit 1)
		(exclude_from_sim no)
		(in_bom yes)
		(on_board yes)
		(dnp no)
		(property "Reference" "R36"
			(at 35.56 212.725 0)
			(effects
				(font
					(size 1.27 1.27)
					(thickness 0.15)
				)
			)
		)
		(property "Value" "R_2k2_0402"
			(at 53.34 223.52 0)
			(effects
				(font
					(size 1.27 1.27)
					(thickness 0.15)
				)
				(justify left bottom)
				(hide yes)
			)
		)
		(property "Footprint" "antmicro-footprints:R_0402_1005Metric"
			(at 53.34 226.06 0)
			(effects
				(font
					(size 1.27 1.27)
					(thickness 0.15)
				)
				(justify left bottom)
				(hide yes)
			)
		)
		(property "Datasheet" "https://www.bourns.com/docs/product-datasheets/cr.pdf"
			(at 53.34 228.6 0)
			(effects
				(font
					(size 1.27 1.27)
					(thickness 0.15)
				)
				(justify left bottom)
				(hide yes)
			)
		)
		(property "Description" "SMD Chip Resistor, 2.2 kohm, ± 1%, 62.5 mW, 0402 [1005 Metric], Thick Film, General Purpose"
			(at 33.02 210.82 0)
			(effects
				(font
					(size 1.27 1.27)
				)
				(hide yes)
			)
		)
		(property "MPN" "CR0402-FX-2201GLF"
			(at 53.34 231.14 0)
			(effects
				(font
					(size 1.27 1.27)
					(thickness 0.15)
				)
				(justify left bottom)
				(hide yes)
			)
		)
		(property "Manufacturer" "Bourns"
			(at 53.34 233.68 0)
			(effects
				(font
					(size 1.27 1.27)
					(thickness 0.15)
				)
				(justify left bottom)
				(hide yes)
			)
		)
		(property "License" "Apache-2.0"
			(at 53.34 236.22 0)
			(effects
				(font
					(size 1.27 1.27)
					(thickness 0.15)
				)
				(justify left bottom)
				(hide yes)
			)
		)
		(property "Val" "2k2"
			(at 39.37 212.09 0)
			(effects
				(font
					(size 1.27 1.27)
					(thickness 0.15)
				)
			)
		)
		(property "Tolerance" "1%"
			(at 53.34 220.98 0)
			(effects
				(font
					(size 1.27 1.27)
				)
				(justify left bottom)
				(hide yes)
			)
		)
		(property "Author" "Antmicro"
			(at 53.34 238.76 0)
			(effects
				(font
					(size 1.27 1.27)
					(thickness 0.15)
				)
				(justify left bottom)
				(hide yes)
			)
		)
		(pin "1"
		)
		(pin "2"
		)
		(instances
			(project "thunderbolt-to-10gbe-adapter"
				(path ""
					(reference "R36")
					(unit 1)
				)
			)
		)
	)
	(symbol
		(lib_id "antmicroInterfaceControllers:JHL6340SLLSQ")
		(at 262.89 45.72 0)
		(unit 2)
		(exclude_from_sim no)
		(in_bom yes)
		(on_board yes)
		(dnp no)
		(fields_autoplaced yes)
		(property "Reference" "U4"
			(at 290.83 36.195 0)
			(effects
				(font
					(size 1.27 1.27)
					(thickness 0.15)
				)
			)
		)
		(property "Value" "JHL6340SLLSQ"
			(at 334.01 48.26 0)
			(effects
				(font
					(size 1.27 1.27)
					(thickness 0.15)
				)
				(justify left bottom)
				(hide yes)
			)
		)
		(property "Footprint" "antmicro-footprints:JHL6340SLLSQ"
			(at 334.01 50.8 0)
			(effects
				(font
					(size 1.27 1.27)
					(thickness 0.15)
				)
				(justify left bottom)
				(hide yes)
			)
		)
		(property "Datasheet" "https://www.thunderbolttechnology.net/sites/default/files/18-241_ThunderboltController_Brief_HI.pdf"
			(at 334.01 53.34 0)
			(effects
				(font
					(size 1.27 1.27)
					(thickness 0.15)
				)
				(justify left bottom)
				(hide yes)
			)
		)
		(property "Description" "Thunderbolt™ 3 Controller, I/O"
			(at 262.89 45.72 0)
			(effects
				(font
					(size 1.27 1.27)
				)
				(hide yes)
			)
		)
		(property "Manufacturer" "Intel"
			(at 334.01 55.88 0)
			(effects
				(font
					(size 1.27 1.27)
					(thickness 0.15)
				)
				(justify left bottom)
				(hide yes)
			)
		)
		(property "MPN" "JHL6340SLLSQ"
			(at 290.83 38.735 0)
			(effects
				(font
					(size 1.27 1.27)
					(thickness 0.15)
				)
			)
		)
		(property "Author" "Antmicro"
			(at 334.01 60.96 0)
			(effects
				(font
					(size 1.27 1.27)
					(thickness 0.15)
				)
				(justify left bottom)
				(hide yes)
			)
		)
		(property "License" "Apache-2.0"
			(at 334.01 63.5 0)
			(effects
				(font
					(size 1.27 1.27)
					(thickness 0.15)
				)
				(justify left bottom)
				(hide yes)
			)
		)
		(pin "V5"
		)
		(pin "Y9"
		)
		(pin "AC5"
		)
		(pin "F12"
		)
		(pin "L13"
		)
		(pin "A13"
		)
		(pin "T23"
		)
		(pin "AA2"
		)
		(pin "L22"
		)
		(pin "R16"
		)
		(pin "N13"
		)
		(pin "D9"
		)
		(pin "T2"
		)
		(pin "R12"
		)
		(pin "U1"
		)
		(pin "R23"
		)
		(pin "J23"
		)
		(pin "T22"
		)
		(pin "L23"
		)
		(pin "B3"
		)
		(pin "V4"
		)
		(pin "N8"
		)
		(pin "AB11"
		)
		(pin "AB4"
		)
		(pin "M6"
		)
		(pin "K22"
		)
		(pin "R5"
		)
		(pin "L15"
		)
		(pin "F13"
		)
		(pin "L12"
		)
		(pin "H20"
		)
		(pin "V15"
		)
		(pin "V22"
		)
		(pin "V19"
		)
		(pin "P23"
		)
		(pin "M18"
		)
		(pin "A4"
		)
		(pin "A9"
		)
		(pin "M23"
		)
		(pin "Y8"
		)
		(pin "Y4"
		)
		(pin "N5"
		)
		(pin "T5"
		)
		(pin "W1"
		)
		(pin "Y11"
		)
		(pin "Y5"
		)
		(pin "B22"
		)
		(pin "B6"
		)
		(pin "V8"
		)
		(pin "V1"
		)
		(pin "A17"
		)
		(pin "Y2"
		)
		(pin "W2"
		)
		(pin "R22"
		)
		(pin "N6"
		)
		(pin "F16"
		)
		(pin "AB13"
		)
		(pin "H4"
		)
		(pin "F22"
		)
		(pin "R4"
		)
		(pin "F23"
		)
		(pin "W11"
		)
		(pin "D13"
		)
		(pin "AC10"
		)
		(pin "M9"
		)
		(pin "V2"
		)
		(pin "L19"
		)
		(pin "T18"
		)
		(pin "L20"
		)
		(pin "H8"
		)
		(pin "AB7"
		)
		(pin "Y23"
		)
		(pin "K1"
		)
		(pin "AC7"
		)
		(pin "H18"
		)
		(pin "C1"
		)
		(pin "N1"
		)
		(pin "AB5"
		)
		(pin "J5"
		)
		(pin "R15"
		)
		(pin "M13"
		)
		(pin "D1"
		)
		(pin "E20"
		)
		(pin "AC11"
		)
		(pin "A5"
		)
		(pin "AB15"
		)
		(pin "L8"
		)
		(pin "D6"
		)
		(pin "D19"
		)
		(pin "V6"
		)
		(pin "N19"
		)
		(pin "T11"
		)
		(pin "W8"
		)
		(pin "C22"
		)
		(pin "H19"
		)
		(pin "L11"
		)
		(pin "AC13"
		)
		(pin "D2"
		)
		(pin "K23"
		)
		(pin "L2"
		)
		(pin "A7"
		)
		(pin "H16"
		)
		(pin "Y16"
		)
		(pin "V12"
		)
		(pin "AB9"
		)
		(pin "M20"
		)
		(pin "N20"
		)
		(pin "R19"
		)
		(pin "U22"
		)
		(pin "AB21"
		)
		(pin "E4"
		)
		(pin "R6"
		)
		(pin "R20"
		)
		(pin "AC1"
		)
		(pin "G2"
		)
		(pin "M8"
		)
		(pin "M16"
		)
		(pin "V20"
		)
		(pin "F18"
		)
		(pin "AB3"
		)
		(pin "AA1"
		)
		(pin "D22"
		)
		(pin "V11"
		)
		(pin "T1"
		)
		(pin "V18"
		)
		(pin "B9"
		)
		(pin "J9"
		)
		(pin "M5"
		)
		(pin "H15"
		)
		(pin "M12"
		)
		(pin "M15"
		)
		(pin "AC9"
		)
		(pin "W23"
		)
		(pin "V9"
		)
		(pin "B8"
		)
		(pin "N16"
		)
		(pin "B14"
		)
		(pin "AC23"
		)
		(pin "W18"
		)
		(pin "M1"
		)
		(pin "N15"
		)
		(pin "AB17"
		)
		(pin "U23"
		)
		(pin "Y22"
		)
		(pin "L9"
		)
		(pin "T13"
		)
		(pin "F11"
		)
		(pin "N4"
		)
		(pin "F19"
		)
		(pin "W6"
		)
		(pin "F15"
		)
		(pin "B7"
		)
		(pin "Y1"
		)
		(pin "A6"
		)
		(pin "B2"
		)
		(pin "B4"
		)
		(pin "R13"
		)
		(pin "K2"
		)
		(pin "N18"
		)
		(pin "B13"
		)
		(pin "T19"
		)
		(pin "W22"
		)
		(pin "H23"
		)
		(pin "T4"
		)
		(pin "L18"
		)
		(pin "E19"
		)
		(pin "H2"
		)
		(pin "L1"
		)
		(pin "F20"
		)
		(pin "B23"
		)
		(pin "R8"
		)
		(pin "M22"
		)
		(pin "F2"
		)
		(pin "E18"
		)
		(pin "R2"
		)
		(pin "W4"
		)
		(pin "B5"
		)
		(pin "W19"
		)
		(pin "N22"
		)
		(pin "D5"
		)
		(pin "W20"
		)
		(pin "W12"
		)
		(pin "B11"
		)
		(pin "R11"
		)
		(pin "E2"
		)
		(pin "D18"
		)
		(pin "T8"
		)
		(pin "L5"
		)
		(pin "M4"
		)
		(pin "T20"
		)
		(pin "A3"
		)
		(pin "AC3"
		)
		(pin "A19"
		)
		(pin "L16"
		)
		(pin "F4"
		)
		(pin "T12"
		)
		(pin "Y18"
		)
		(pin "T16"
		)
		(pin "AB19"
		)
		(pin "B12"
		)
		(pin "E23"
		)
		(pin "E1"
		)
		(pin "T6"
		)
		(pin "Y19"
		)
		(pin "T15"
		)
		(pin "P22"
		)
		(pin "AB16"
		)
		(pin "AC4"
		)
		(pin "D15"
		)
		(pin "G1"
		)
		(pin "A8"
		)
		(pin "Y12"
		)
		(pin "J4"
		)
		(pin "J1"
		)
		(pin "E22"
		)
		(pin "D20"
		)
		(pin "M2"
		)
		(pin "V23"
		)
		(pin "AB10"
		)
		(pin "AB2"
		)
		(pin "AC15"
		)
		(pin "D23"
		)
		(pin "A23"
		)
		(pin "C23"
		)
		(pin "J2"
		)
		(pin "A21"
		)
		(pin "F1"
		)
		(pin "H5"
		)
		(pin "N11"
		)
		(pin "B20"
		)
		(pin "H22"
		)
		(pin "AA23"
		)
		(pin "E13"
		)
		(pin "J12"
		)
		(pin "W9"
		)
		(pin "H9"
		)
		(pin "B19"
		)
		(pin "AB8"
		)
		(pin "AB22"
		)
		(pin "AB6"
		)
		(pin "AB20"
		)
		(pin "AC2"
		)
		(pin "E9"
		)
		(pin "J11"
		)
		(pin "L4"
		)
		(pin "J8"
		)
		(pin "AC22"
		)
		(pin "J13"
		)
		(pin "N12"
		)
		(pin "J15"
		)
		(pin "B18"
		)
		(pin "Y15"
		)
		(pin "U2"
		)
		(pin "AC12"
		)
		(pin "D16"
		)
		(pin "AB14"
		)
		(pin "AC6"
		)
		(pin "A14"
		)
		(pin "V13"
		)
		(pin "G22"
		)
		(pin "Y13"
		)
		(pin "B16"
		)
		(pin "AB18"
		)
		(pin "B17"
		)
		(pin "A20"
		)
		(pin "AB12"
		)
		(pin "R1"
		)
		(pin "AC20"
		)
		(pin "H12"
		)
		(pin "A2"
		)
		(pin "F5"
		)
		(pin "E6"
		)
		(pin "A10"
		)
		(pin "A12"
		)
		(pin "H11"
		)
		(pin "F9"
		)
		(pin "A1"
		)
		(pin "AB1"
		)
		(pin "E8"
		)
		(pin "A11"
		)
		(pin "L6"
		)
		(pin "B21"
		)
		(pin "AB23"
		)
		(pin "W13"
		)
		(pin "P2"
		)
		(pin "W16"
		)
		(pin "AC16"
		)
		(pin "H6"
		)
		(pin "Y6"
		)
		(pin "A15"
		)
		(pin "J6"
		)
		(pin "V16"
		)
		(pin "N9"
		)
		(pin "AC21"
		)
		(pin "J19"
		)
		(pin "J20"
		)
		(pin "AC17"
		)
		(pin "AC19"
		)
		(pin "M11"
		)
		(pin "D4"
		)
		(pin "P1"
		)
		(pin "W5"
		)
		(pin "R18"
		)
		(pin "E16"
		)
		(pin "N23"
		)
		(pin "A22"
		)
		(pin "R9"
		)
		(pin "D8"
		)
		(pin "E15"
		)
		(pin "M19"
		)
		(pin "Y20"
		)
		(pin "T9"
		)
		(pin "H13"
		)
		(pin "W15"
		)
		(pin "B10"
		)
		(pin "AC14"
		)
		(pin "AC18"
		)
		(pin "C2"
		)
		(pin "E5"
		)
		(pin "J22"
		)
		(pin "J18"
		)
		(pin "J16"
		)
		(pin "AC8"
		)
		(pin "B1"
		)
		(pin "N2"
		)
		(pin "E11"
		)
		(pin "A18"
		)
		(pin "H1"
		)
		(pin "G23"
		)
		(pin "A16"
		)
		(pin "D11"
		)
		(pin "B15"
		)
		(pin "F8"
		)
		(pin "E12"
		)
		(pin "AA22"
		)
		(pin "D12"
		)
		(pin "F6"
		)
		(instances
			(project "thunderbolt-to-10gbe-adapter"
				(path ""
					(reference "U4")
					(unit 2)
				)
			)
		)
	)
)
